FILE_TYPE = MACRO_DRAWING;
SET COLOR_WIRE YELLOW;
SET COLOR_PROP ORANGE;
SET COLOR_DOT WHITE;
SET COLOR_ARC YELLOW;
SET COLOR_BODY GREEN;
SET COLOR_NOTE PURPLE;
SET PROP_DISPLAY VALUE;
SET PAGE_NUMBER P353;
FORCEADD OFFPAGE..1
(-2850 1625);
FORCEPROP 2 LAST $XR0 23 
J 0
(-3071 1625);
DISPLAY 0.638298 (-3071 1625);
PAINT MONO (-3071 1625);
FORCEPROP 2 LAST CDS_LIB standard
J 0
(-2850 1625);
DISPLAY INVISIBLE (-2850 1625);
FORCEPROP 1 LAST OFFPAGE TRUE
J 0
(-2525 1500);
DISPLAY 0.872340 (-2525 1500);
DISPLAY INVISIBLE (-2525 1500);
FORCEPROP 1 LAST COMMENT_BODY TRUE
J 0
(-2725 1525);
DISPLAY 0.872340 (-2725 1525);
PAINT GREEN (-2725 1525);
DISPLAY INVISIBLE (-2725 1525);
FORCEPROP 2 LAST PATH I209
J 0
(-3100 1675);
DISPLAY 1.021277 (-3100 1675);
DISPLAY INVISIBLE (-3100 1675);
FORCEADD OFFPAGE..1
(-2850 1575);
FORCEPROP 2 LAST $XR0 23 
J 0
(-3071 1575);
DISPLAY 0.638298 (-3071 1575);
PAINT MONO (-3071 1575);
FORCEPROP 2 LAST CDS_LIB standard
J 0
(-2850 1575);
DISPLAY INVISIBLE (-2850 1575);
FORCEPROP 1 LAST OFFPAGE TRUE
J 0
(-2525 1450);
DISPLAY 0.872340 (-2525 1450);
DISPLAY INVISIBLE (-2525 1450);
FORCEPROP 1 LAST COMMENT_BODY TRUE
J 0
(-2725 1475);
DISPLAY 0.872340 (-2725 1475);
PAINT GREEN (-2725 1475);
DISPLAY INVISIBLE (-2725 1475);
FORCEPROP 2 LAST PATH I210
J 0
(-3100 1625);
DISPLAY 1.021277 (-3100 1625);
DISPLAY INVISIBLE (-3100 1625);
FORCEADD OFFPAGE..1
(-2850 3550);
FORCEPROP 2 LAST $XR0 23 
J 0
(-3071 3550);
DISPLAY 0.638298 (-3071 3550);
PAINT MONO (-3071 3550);
FORCEPROP 2 LAST CDS_LIB standard
J 0
(-2850 3550);
DISPLAY INVISIBLE (-2850 3550);
FORCEPROP 1 LAST OFFPAGE TRUE
J 0
(-2525 3425);
DISPLAY 0.872340 (-2525 3425);
DISPLAY INVISIBLE (-2525 3425);
FORCEPROP 1 LAST COMMENT_BODY TRUE
J 0
(-2725 3450);
DISPLAY 0.872340 (-2725 3450);
PAINT GREEN (-2725 3450);
DISPLAY INVISIBLE (-2725 3450);
FORCEPROP 2 LAST PATH I211
J 0
(-3100 3600);
DISPLAY 1.021277 (-3100 3600);
DISPLAY INVISIBLE (-3100 3600);
FORCEADD OFFPAGE..1
(-2850 3600);
FORCEPROP 2 LAST $XR0 23 
J 0
(-3071 3600);
DISPLAY 0.638298 (-3071 3600);
PAINT MONO (-3071 3600);
FORCEPROP 2 LAST CDS_LIB standard
J 0
(-2850 3600);
DISPLAY INVISIBLE (-2850 3600);
FORCEPROP 1 LAST OFFPAGE TRUE
J 0
(-2525 3475);
DISPLAY 0.872340 (-2525 3475);
DISPLAY INVISIBLE (-2525 3475);
FORCEPROP 1 LAST COMMENT_BODY TRUE
J 0
(-2725 3500);
DISPLAY 0.872340 (-2725 3500);
PAINT GREEN (-2725 3500);
DISPLAY INVISIBLE (-2725 3500);
FORCEPROP 2 LAST PATH I212
J 0
(-3100 3650);
DISPLAY 1.021277 (-3100 3650);
DISPLAY INVISIBLE (-3100 3650);
FORCEADD TAP..1
R 2
(-1900 150);
FORCEPROP 3 LASTPIN (-1850 150) SIG_NAME P5E_CPU0_G3_TX_DP<0>
J 0
(-1840 160);
DISPLAY 0.659574 (-1840 160);
PAINT MONO (-1840 160);
DISPLAY INVISIBLE (-1840 160);
FORCEPROP 1 LASTPIN (-1850 150) BN 0
J 2
(-1838 158);
DISPLAY 0.680851 (-1838 158);
PAINT GREEN (-1838 158);
FORCEPROP 2 LAST CDS_LIB standard
J 0
(-1900 150);
DISPLAY INVISIBLE (-1900 150);
FORCEPROP 1 LAST BODY_TYPE PLUMBING
J 2
(-1900 200);
DISPLAY 0.872340 (-1900 200);
PAINT GREEN (-1900 200);
DISPLAY INVISIBLE (-1900 200);
FORCEPROP 1 LAST HDL_TAP TRUE
J 2
(-2225 25);
DISPLAY 0.872340 (-2225 25);
DISPLAY INVISIBLE (-2225 25);
FORCEPROP 1 LAST PATH I213
J 2
(-1898 150);
DISPLAY 0.872340 (-1898 150);
PAINT GREEN (-1898 150);
DISPLAY INVISIBLE (-1898 150);
FORCEADD TAP..1
R 2
(-1900 350);
FORCEPROP 3 LASTPIN (-1850 350) SIG_NAME P5E_CPU0_G3_TX_DP<1>
J 0
(-1840 360);
DISPLAY 0.659574 (-1840 360);
PAINT MONO (-1840 360);
DISPLAY INVISIBLE (-1840 360);
FORCEPROP 1 LASTPIN (-1850 350) BN 1
J 2
(-1838 358);
DISPLAY 0.680851 (-1838 358);
PAINT GREEN (-1838 358);
FORCEPROP 2 LAST CDS_LIB standard
J 0
(-1900 350);
DISPLAY INVISIBLE (-1900 350);
FORCEPROP 1 LAST BODY_TYPE PLUMBING
J 2
(-1900 400);
DISPLAY 0.872340 (-1900 400);
PAINT GREEN (-1900 400);
DISPLAY INVISIBLE (-1900 400);
FORCEPROP 1 LAST HDL_TAP TRUE
J 2
(-2225 225);
DISPLAY 0.872340 (-2225 225);
DISPLAY INVISIBLE (-2225 225);
FORCEPROP 1 LAST PATH I214
J 2
(-1898 350);
DISPLAY 0.872340 (-1898 350);
PAINT GREEN (-1898 350);
DISPLAY INVISIBLE (-1898 350);
FORCEADD TAP..1
R 2
(-1650 200);
FORCEPROP 3 LASTPIN (-1600 200) SIG_NAME P5E_CPU0_G3_TX_DN<0>
J 0
(-1590 210);
DISPLAY 0.659574 (-1590 210);
PAINT MONO (-1590 210);
DISPLAY INVISIBLE (-1590 210);
FORCEPROP 1 LASTPIN (-1600 200) BN 0
J 2
(-1588 208);
DISPLAY 0.680851 (-1588 208);
PAINT GREEN (-1588 208);
FORCEPROP 2 LAST CDS_LIB standard
J 0
(-1650 200);
DISPLAY INVISIBLE (-1650 200);
FORCEPROP 1 LAST BODY_TYPE PLUMBING
J 2
(-1650 250);
DISPLAY 0.872340 (-1650 250);
PAINT GREEN (-1650 250);
DISPLAY INVISIBLE (-1650 250);
FORCEPROP 1 LAST HDL_TAP TRUE
J 2
(-1975 75);
DISPLAY 0.872340 (-1975 75);
DISPLAY INVISIBLE (-1975 75);
FORCEPROP 1 LAST PATH I215
J 2
(-1648 200);
DISPLAY 0.872340 (-1648 200);
PAINT GREEN (-1648 200);
DISPLAY INVISIBLE (-1648 200);
FORCEADD TAP..1
R 2
(-1650 400);
FORCEPROP 3 LASTPIN (-1600 400) SIG_NAME P5E_CPU0_G3_TX_DN<1>
J 0
(-1590 410);
DISPLAY 0.659574 (-1590 410);
PAINT MONO (-1590 410);
DISPLAY INVISIBLE (-1590 410);
FORCEPROP 1 LASTPIN (-1600 400) BN 1
J 2
(-1588 408);
DISPLAY 0.680851 (-1588 408);
PAINT GREEN (-1588 408);
FORCEPROP 2 LAST CDS_LIB standard
J 0
(-1650 400);
DISPLAY INVISIBLE (-1650 400);
FORCEPROP 1 LAST BODY_TYPE PLUMBING
J 2
(-1650 450);
DISPLAY 0.872340 (-1650 450);
PAINT GREEN (-1650 450);
DISPLAY INVISIBLE (-1650 450);
FORCEPROP 1 LAST HDL_TAP TRUE
J 2
(-1975 275);
DISPLAY 0.872340 (-1975 275);
DISPLAY INVISIBLE (-1975 275);
FORCEPROP 1 LAST PATH I216
J 2
(-1648 400);
DISPLAY 0.872340 (-1648 400);
PAINT GREEN (-1648 400);
DISPLAY INVISIBLE (-1648 400);
FORCEADD TAP..1
R 2
(-1900 750);
FORCEPROP 3 LASTPIN (-1850 750) SIG_NAME P5E_CPU0_G3_TX_DP<3>
J 0
(-1840 760);
DISPLAY 0.659574 (-1840 760);
PAINT MONO (-1840 760);
DISPLAY INVISIBLE (-1840 760);
FORCEPROP 1 LASTPIN (-1850 750) BN 3
J 2
(-1838 758);
DISPLAY 0.680851 (-1838 758);
PAINT GREEN (-1838 758);
FORCEPROP 2 LAST CDS_LIB standard
J 0
(-1900 750);
DISPLAY INVISIBLE (-1900 750);
FORCEPROP 1 LAST BODY_TYPE PLUMBING
J 2
(-1900 800);
DISPLAY 0.872340 (-1900 800);
PAINT GREEN (-1900 800);
DISPLAY INVISIBLE (-1900 800);
FORCEPROP 1 LAST HDL_TAP TRUE
J 2
(-2225 625);
DISPLAY 0.872340 (-2225 625);
DISPLAY INVISIBLE (-2225 625);
FORCEPROP 1 LAST PATH I217
J 2
(-1898 750);
DISPLAY 0.872340 (-1898 750);
PAINT GREEN (-1898 750);
DISPLAY INVISIBLE (-1898 750);
FORCEADD TAP..1
R 2
(-1900 550);
FORCEPROP 3 LASTPIN (-1850 550) SIG_NAME P5E_CPU0_G3_TX_DP<2>
J 0
(-1840 560);
DISPLAY 0.659574 (-1840 560);
PAINT MONO (-1840 560);
DISPLAY INVISIBLE (-1840 560);
FORCEPROP 1 LASTPIN (-1850 550) BN 2
J 2
(-1838 558);
DISPLAY 0.680851 (-1838 558);
PAINT GREEN (-1838 558);
FORCEPROP 2 LAST CDS_LIB standard
J 0
(-1900 550);
DISPLAY INVISIBLE (-1900 550);
FORCEPROP 1 LAST BODY_TYPE PLUMBING
J 2
(-1900 600);
DISPLAY 0.872340 (-1900 600);
PAINT GREEN (-1900 600);
DISPLAY INVISIBLE (-1900 600);
FORCEPROP 1 LAST HDL_TAP TRUE
J 2
(-2225 425);
DISPLAY 0.872340 (-2225 425);
DISPLAY INVISIBLE (-2225 425);
FORCEPROP 1 LAST PATH I218
J 2
(-1898 550);
DISPLAY 0.872340 (-1898 550);
PAINT GREEN (-1898 550);
DISPLAY INVISIBLE (-1898 550);
FORCEADD TAP..1
R 2
(-1900 950);
FORCEPROP 3 LASTPIN (-1850 950) SIG_NAME P5E_CPU0_G3_TX_DP<4>
J 0
(-1840 960);
DISPLAY 0.659574 (-1840 960);
PAINT MONO (-1840 960);
DISPLAY INVISIBLE (-1840 960);
FORCEPROP 1 LASTPIN (-1850 950) BN 4
J 2
(-1838 958);
DISPLAY 0.680851 (-1838 958);
PAINT GREEN (-1838 958);
FORCEPROP 2 LAST CDS_LIB standard
J 0
(-1900 950);
DISPLAY INVISIBLE (-1900 950);
FORCEPROP 1 LAST BODY_TYPE PLUMBING
J 2
(-1900 1000);
DISPLAY 0.872340 (-1900 1000);
PAINT GREEN (-1900 1000);
DISPLAY INVISIBLE (-1900 1000);
FORCEPROP 1 LAST HDL_TAP TRUE
J 2
(-2225 825);
DISPLAY 0.872340 (-2225 825);
DISPLAY INVISIBLE (-2225 825);
FORCEPROP 1 LAST PATH I219
J 2
(-1898 950);
DISPLAY 0.872340 (-1898 950);
PAINT GREEN (-1898 950);
DISPLAY INVISIBLE (-1898 950);
FORCEADD TAP..1
R 2
(-1650 600);
FORCEPROP 3 LASTPIN (-1600 600) SIG_NAME P5E_CPU0_G3_TX_DN<2>
J 0
(-1590 610);
DISPLAY 0.659574 (-1590 610);
PAINT MONO (-1590 610);
DISPLAY INVISIBLE (-1590 610);
FORCEPROP 1 LASTPIN (-1600 600) BN 2
J 2
(-1588 608);
DISPLAY 0.680851 (-1588 608);
PAINT GREEN (-1588 608);
FORCEPROP 2 LAST CDS_LIB standard
J 0
(-1650 600);
DISPLAY INVISIBLE (-1650 600);
FORCEPROP 1 LAST BODY_TYPE PLUMBING
J 2
(-1650 650);
DISPLAY 0.872340 (-1650 650);
PAINT GREEN (-1650 650);
DISPLAY INVISIBLE (-1650 650);
FORCEPROP 1 LAST HDL_TAP TRUE
J 2
(-1975 475);
DISPLAY 0.872340 (-1975 475);
DISPLAY INVISIBLE (-1975 475);
FORCEPROP 1 LAST PATH I220
J 2
(-1648 600);
DISPLAY 0.872340 (-1648 600);
PAINT GREEN (-1648 600);
DISPLAY INVISIBLE (-1648 600);
FORCEADD TAP..1
R 2
(-1650 800);
FORCEPROP 3 LASTPIN (-1600 800) SIG_NAME P5E_CPU0_G3_TX_DN<3>
J 0
(-1590 810);
DISPLAY 0.659574 (-1590 810);
PAINT MONO (-1590 810);
DISPLAY INVISIBLE (-1590 810);
FORCEPROP 1 LASTPIN (-1600 800) BN 3
J 2
(-1588 808);
DISPLAY 0.680851 (-1588 808);
PAINT GREEN (-1588 808);
FORCEPROP 2 LAST CDS_LIB standard
J 0
(-1650 800);
DISPLAY INVISIBLE (-1650 800);
FORCEPROP 1 LAST BODY_TYPE PLUMBING
J 2
(-1650 850);
DISPLAY 0.872340 (-1650 850);
PAINT GREEN (-1650 850);
DISPLAY INVISIBLE (-1650 850);
FORCEPROP 1 LAST HDL_TAP TRUE
J 2
(-1975 675);
DISPLAY 0.872340 (-1975 675);
DISPLAY INVISIBLE (-1975 675);
FORCEPROP 1 LAST PATH I221
J 2
(-1648 800);
DISPLAY 0.872340 (-1648 800);
PAINT GREEN (-1648 800);
DISPLAY INVISIBLE (-1648 800);
FORCEADD TAP..1
R 2
(-1650 1000);
FORCEPROP 3 LASTPIN (-1600 1000) SIG_NAME P5E_CPU0_G3_TX_DN<4>
J 0
(-1590 1010);
DISPLAY 0.659574 (-1590 1010);
PAINT MONO (-1590 1010);
DISPLAY INVISIBLE (-1590 1010);
FORCEPROP 1 LASTPIN (-1600 1000) BN 4
J 2
(-1588 1008);
DISPLAY 0.680851 (-1588 1008);
PAINT GREEN (-1588 1008);
FORCEPROP 2 LAST CDS_LIB standard
J 0
(-1650 1000);
DISPLAY INVISIBLE (-1650 1000);
FORCEPROP 1 LAST BODY_TYPE PLUMBING
J 2
(-1650 1050);
DISPLAY 0.872340 (-1650 1050);
PAINT GREEN (-1650 1050);
DISPLAY INVISIBLE (-1650 1050);
FORCEPROP 1 LAST HDL_TAP TRUE
J 2
(-1975 875);
DISPLAY 0.872340 (-1975 875);
DISPLAY INVISIBLE (-1975 875);
FORCEPROP 1 LAST PATH I222
J 2
(-1648 1000);
DISPLAY 0.872340 (-1648 1000);
PAINT GREEN (-1648 1000);
DISPLAY INVISIBLE (-1648 1000);
FORCEADD TAP..1
R 2
(-1900 1150);
FORCEPROP 3 LASTPIN (-1850 1150) SIG_NAME P5E_CPU0_G3_TX_DP<5>
J 0
(-1840 1160);
DISPLAY 0.659574 (-1840 1160);
PAINT MONO (-1840 1160);
DISPLAY INVISIBLE (-1840 1160);
FORCEPROP 1 LASTPIN (-1850 1150) BN 5
J 2
(-1838 1158);
DISPLAY 0.680851 (-1838 1158);
PAINT GREEN (-1838 1158);
FORCEPROP 2 LAST CDS_LIB standard
J 0
(-1900 1150);
DISPLAY INVISIBLE (-1900 1150);
FORCEPROP 1 LAST BODY_TYPE PLUMBING
J 2
(-1900 1200);
DISPLAY 0.872340 (-1900 1200);
PAINT GREEN (-1900 1200);
DISPLAY INVISIBLE (-1900 1200);
FORCEPROP 1 LAST HDL_TAP TRUE
J 2
(-2225 1025);
DISPLAY 0.872340 (-2225 1025);
DISPLAY INVISIBLE (-2225 1025);
FORCEPROP 1 LAST PATH I223
J 2
(-1898 1150);
DISPLAY 0.872340 (-1898 1150);
PAINT GREEN (-1898 1150);
DISPLAY INVISIBLE (-1898 1150);
FORCEADD TAP..1
R 2
(-1900 1350);
FORCEPROP 3 LASTPIN (-1850 1350) SIG_NAME P5E_CPU0_G3_TX_DP<6>
J 0
(-1840 1360);
DISPLAY 0.659574 (-1840 1360);
PAINT MONO (-1840 1360);
DISPLAY INVISIBLE (-1840 1360);
FORCEPROP 1 LASTPIN (-1850 1350) BN 6
J 2
(-1838 1358);
DISPLAY 0.680851 (-1838 1358);
PAINT GREEN (-1838 1358);
FORCEPROP 2 LAST CDS_LIB standard
J 0
(-1900 1350);
DISPLAY INVISIBLE (-1900 1350);
FORCEPROP 1 LAST BODY_TYPE PLUMBING
J 2
(-1900 1400);
DISPLAY 0.872340 (-1900 1400);
PAINT GREEN (-1900 1400);
DISPLAY INVISIBLE (-1900 1400);
FORCEPROP 1 LAST HDL_TAP TRUE
J 2
(-2225 1225);
DISPLAY 0.872340 (-2225 1225);
DISPLAY INVISIBLE (-2225 1225);
FORCEPROP 1 LAST PATH I224
J 2
(-1898 1350);
DISPLAY 0.872340 (-1898 1350);
PAINT GREEN (-1898 1350);
DISPLAY INVISIBLE (-1898 1350);
FORCEADD TAP..1
R 2
(-1650 1200);
FORCEPROP 3 LASTPIN (-1600 1200) SIG_NAME P5E_CPU0_G3_TX_DN<5>
J 0
(-1590 1210);
DISPLAY 0.659574 (-1590 1210);
PAINT MONO (-1590 1210);
DISPLAY INVISIBLE (-1590 1210);
FORCEPROP 1 LASTPIN (-1600 1200) BN 5
J 2
(-1588 1208);
DISPLAY 0.680851 (-1588 1208);
PAINT GREEN (-1588 1208);
FORCEPROP 2 LAST CDS_LIB standard
J 0
(-1650 1200);
DISPLAY INVISIBLE (-1650 1200);
FORCEPROP 1 LAST BODY_TYPE PLUMBING
J 2
(-1650 1250);
DISPLAY 0.872340 (-1650 1250);
PAINT GREEN (-1650 1250);
DISPLAY INVISIBLE (-1650 1250);
FORCEPROP 1 LAST HDL_TAP TRUE
J 2
(-1975 1075);
DISPLAY 0.872340 (-1975 1075);
DISPLAY INVISIBLE (-1975 1075);
FORCEPROP 1 LAST PATH I225
J 2
(-1648 1200);
DISPLAY 0.872340 (-1648 1200);
PAINT GREEN (-1648 1200);
DISPLAY INVISIBLE (-1648 1200);
FORCEADD TAP..1
R 2
(-1650 1400);
FORCEPROP 3 LASTPIN (-1600 1400) SIG_NAME P5E_CPU0_G3_TX_DN<6>
J 0
(-1590 1410);
DISPLAY 0.659574 (-1590 1410);
PAINT MONO (-1590 1410);
DISPLAY INVISIBLE (-1590 1410);
FORCEPROP 1 LASTPIN (-1600 1400) BN 6
J 2
(-1588 1408);
DISPLAY 0.680851 (-1588 1408);
PAINT GREEN (-1588 1408);
FORCEPROP 2 LAST CDS_LIB standard
J 0
(-1650 1400);
DISPLAY INVISIBLE (-1650 1400);
FORCEPROP 1 LAST BODY_TYPE PLUMBING
J 2
(-1650 1450);
DISPLAY 0.872340 (-1650 1450);
PAINT GREEN (-1650 1450);
DISPLAY INVISIBLE (-1650 1450);
FORCEPROP 1 LAST HDL_TAP TRUE
J 2
(-1975 1275);
DISPLAY 0.872340 (-1975 1275);
DISPLAY INVISIBLE (-1975 1275);
FORCEPROP 1 LAST PATH I226
J 2
(-1648 1400);
DISPLAY 0.872340 (-1648 1400);
PAINT GREEN (-1648 1400);
DISPLAY INVISIBLE (-1648 1400);
FORCEADD TAP..1
R 2
(-1900 1550);
FORCEPROP 3 LASTPIN (-1850 1550) SIG_NAME P5E_CPU0_G3_TX_DP<7>
J 0
(-1840 1560);
DISPLAY 0.659574 (-1840 1560);
PAINT MONO (-1840 1560);
DISPLAY INVISIBLE (-1840 1560);
FORCEPROP 1 LASTPIN (-1850 1550) BN 7
J 2
(-1838 1558);
DISPLAY 0.680851 (-1838 1558);
PAINT GREEN (-1838 1558);
FORCEPROP 2 LAST CDS_LIB standard
J 0
(-1900 1550);
DISPLAY INVISIBLE (-1900 1550);
FORCEPROP 1 LAST BODY_TYPE PLUMBING
J 2
(-1900 1600);
DISPLAY 0.872340 (-1900 1600);
PAINT GREEN (-1900 1600);
DISPLAY INVISIBLE (-1900 1600);
FORCEPROP 1 LAST HDL_TAP TRUE
J 2
(-2225 1425);
DISPLAY 0.872340 (-2225 1425);
DISPLAY INVISIBLE (-2225 1425);
FORCEPROP 1 LAST PATH I227
J 2
(-1898 1550);
DISPLAY 0.872340 (-1898 1550);
PAINT GREEN (-1898 1550);
DISPLAY INVISIBLE (-1898 1550);
FORCEADD TAP..1
R 2
(-1650 1600);
FORCEPROP 3 LASTPIN (-1600 1600) SIG_NAME P5E_CPU0_G3_TX_DN<7>
J 0
(-1590 1610);
DISPLAY 0.659574 (-1590 1610);
PAINT MONO (-1590 1610);
DISPLAY INVISIBLE (-1590 1610);
FORCEPROP 1 LASTPIN (-1600 1600) BN 7
J 2
(-1588 1608);
DISPLAY 0.680851 (-1588 1608);
PAINT GREEN (-1588 1608);
FORCEPROP 2 LAST CDS_LIB standard
J 0
(-1650 1600);
DISPLAY INVISIBLE (-1650 1600);
FORCEPROP 1 LAST BODY_TYPE PLUMBING
J 2
(-1650 1650);
DISPLAY 0.872340 (-1650 1650);
PAINT GREEN (-1650 1650);
DISPLAY INVISIBLE (-1650 1650);
FORCEPROP 1 LAST HDL_TAP TRUE
J 2
(-1975 1475);
DISPLAY 0.872340 (-1975 1475);
DISPLAY INVISIBLE (-1975 1475);
FORCEPROP 1 LAST PATH I228
J 2
(-1648 1600);
DISPLAY 0.872340 (-1648 1600);
PAINT GREEN (-1648 1600);
DISPLAY INVISIBLE (-1648 1600);
FORCEADD Q_CAP_DIFFBUS..2
R 2
(-925 150);
FORCEPROP 1 LAST LOCATION C1579
J 2
(-675 175);
DISPLAY 0.723404 (-675 175);
PAINT GREEN (-675 175);
FORCEPROP 2 LAST $SEC 1
J 2
(-750 225);
DISPLAY 0.680851 (-750 225);
PAINT MONO (-750 225);
DISPLAY INVISIBLE (-750 225);
FORCEPROP 2 LAST CDS_SEC 1
J 2
(-750 225);
DISPLAY 0.680851 (-750 225);
DISPLAY INVISIBLE (-750 225);
FORCEPROP 2 LASTPIN (-850 150) $PN 1
J 0
(-840 160);
DISPLAY 0.808511 (-840 160);
FORCEPROP 2 LASTPIN (-1000 150) $PN 2
J 2
(-1010 160);
DISPLAY 0.808511 (-1010 160);
FORCEPROP 2 LAST VALUE DIFF BUS_0.22UF
J 2
(-1075 150);
DISPLAY 0.553191 (-1075 150);
FORCEPROP 1 LAST PIN_NAMES_ROTATE TRUE
J 2
(-925 150);
DISPLAY 0.489362 (-925 150);
PAINT GREEN (-925 150);
DISPLAY INVISIBLE (-925 150);
FORCEPROP 2 LAST CDS_LIB pure_quanta
J 2
(-925 150);
DISPLAY INVISIBLE (-925 150);
FORCEPROP 1 LAST CDS_LMAN_SYM_OUTLINE -25,50,25,-50
J 2
(-925 150);
DISPLAY 0.468085 (-925 150);
PAINT GREEN (-925 150);
DISPLAY INVISIBLE (-925 150);
FORCEPROP 2 LAST VOLTAGE 6.3V
J 2
(-1275 200);
DISPLAY 0.553191 (-1275 200);
DISPLAY INVISIBLE (-1275 200);
FORCEPROP 1 LAST MATERIAL X6S
J 2
(-916 229);
DISPLAY 0.574468 (-916 229);
PAINT GREEN (-916 229);
DISPLAY INVISIBLE (-916 229);
FORCEPROP 2 LAST PACK_TYPE C0201
J 2
(-1100 200);
DISPLAY 0.553191 (-1100 200);
DISPLAY INVISIBLE (-1100 200);
FORCEPROP 2 LAST TOLERANCE 20%
J 2
(-1000 200);
DISPLAY 0.553191 (-1000 200);
DISPLAY INVISIBLE (-1000 200);
FORCEPROP 1 LAST PART_NUMBER SP_CH4221MEE01
J 2
(-1041 238);
DISPLAY 0.574468 (-1041 238);
PAINT GREEN (-1041 238);
DISPLAY INVISIBLE (-1041 238);
FORCEPROP 1 LAST PATH I229
J 2
(-925 150);
DISPLAY 0.723404 (-925 150);
DISPLAY INVISIBLE (-925 150);
FORCEADD Q_CAP_DIFFBUS..2
R 2
(-925 200);
FORCEPROP 1 LAST LOCATION C1578
J 2
(-675 225);
DISPLAY 0.723404 (-675 225);
PAINT GREEN (-675 225);
FORCEPROP 2 LAST $SEC 1
J 2
(-750 275);
DISPLAY 0.680851 (-750 275);
PAINT MONO (-750 275);
DISPLAY INVISIBLE (-750 275);
FORCEPROP 2 LAST CDS_SEC 1
J 2
(-750 275);
DISPLAY 0.680851 (-750 275);
DISPLAY INVISIBLE (-750 275);
FORCEPROP 2 LASTPIN (-850 200) $PN 1
J 0
(-840 210);
DISPLAY 0.808511 (-840 210);
FORCEPROP 2 LASTPIN (-1000 200) $PN 2
J 2
(-1010 210);
DISPLAY 0.808511 (-1010 210);
FORCEPROP 2 LAST VALUE DIFF BUS_0.22UF
J 2
(-1075 200);
DISPLAY 0.553191 (-1075 200);
FORCEPROP 1 LAST PIN_NAMES_ROTATE TRUE
J 2
(-925 200);
DISPLAY 0.489362 (-925 200);
PAINT GREEN (-925 200);
DISPLAY INVISIBLE (-925 200);
FORCEPROP 2 LAST CDS_LIB pure_quanta
J 2
(-925 200);
DISPLAY INVISIBLE (-925 200);
FORCEPROP 1 LAST CDS_LMAN_SYM_OUTLINE -25,50,25,-50
J 2
(-925 200);
DISPLAY 0.468085 (-925 200);
PAINT GREEN (-925 200);
DISPLAY INVISIBLE (-925 200);
FORCEPROP 2 LAST VOLTAGE 6.3V
J 2
(-1275 250);
DISPLAY 0.553191 (-1275 250);
DISPLAY INVISIBLE (-1275 250);
FORCEPROP 1 LAST MATERIAL X6S
J 2
(-916 279);
DISPLAY 0.574468 (-916 279);
PAINT GREEN (-916 279);
DISPLAY INVISIBLE (-916 279);
FORCEPROP 2 LAST PACK_TYPE C0201
J 2
(-1100 250);
DISPLAY 0.553191 (-1100 250);
DISPLAY INVISIBLE (-1100 250);
FORCEPROP 2 LAST TOLERANCE 20%
J 2
(-1000 250);
DISPLAY 0.553191 (-1000 250);
DISPLAY INVISIBLE (-1000 250);
FORCEPROP 1 LAST PART_NUMBER SP_CH4221MEE01
J 2
(-1041 288);
DISPLAY 0.574468 (-1041 288);
PAINT GREEN (-1041 288);
DISPLAY INVISIBLE (-1041 288);
FORCEPROP 1 LAST PATH I230
J 2
(-925 200);
DISPLAY 0.723404 (-925 200);
DISPLAY INVISIBLE (-925 200);
FORCEADD Q_CAP_DIFFBUS..2
R 2
(-925 550);
FORCEPROP 1 LAST LOCATION C1575
J 2
(-675 575);
DISPLAY 0.723404 (-675 575);
PAINT GREEN (-675 575);
FORCEPROP 2 LAST $SEC 1
J 2
(-750 625);
DISPLAY 0.680851 (-750 625);
PAINT MONO (-750 625);
DISPLAY INVISIBLE (-750 625);
FORCEPROP 2 LAST CDS_SEC 1
J 2
(-750 625);
DISPLAY 0.680851 (-750 625);
DISPLAY INVISIBLE (-750 625);
FORCEPROP 2 LASTPIN (-850 550) $PN 1
J 0
(-840 560);
DISPLAY 0.808511 (-840 560);
FORCEPROP 2 LASTPIN (-1000 550) $PN 2
J 2
(-1010 560);
DISPLAY 0.808511 (-1010 560);
FORCEPROP 2 LAST VALUE DIFF BUS_0.22UF
J 2
(-1075 550);
DISPLAY 0.553191 (-1075 550);
FORCEPROP 1 LAST PIN_NAMES_ROTATE TRUE
J 2
(-925 550);
DISPLAY 0.489362 (-925 550);
PAINT GREEN (-925 550);
DISPLAY INVISIBLE (-925 550);
FORCEPROP 2 LAST CDS_LIB pure_quanta
J 2
(-925 550);
DISPLAY INVISIBLE (-925 550);
FORCEPROP 1 LAST CDS_LMAN_SYM_OUTLINE -25,50,25,-50
J 2
(-925 550);
DISPLAY 0.468085 (-925 550);
PAINT GREEN (-925 550);
DISPLAY INVISIBLE (-925 550);
FORCEPROP 2 LAST VOLTAGE 6.3V
J 2
(-1275 600);
DISPLAY 0.553191 (-1275 600);
DISPLAY INVISIBLE (-1275 600);
FORCEPROP 1 LAST MATERIAL X6S
J 2
(-916 629);
DISPLAY 0.574468 (-916 629);
PAINT GREEN (-916 629);
DISPLAY INVISIBLE (-916 629);
FORCEPROP 2 LAST PACK_TYPE C0201
J 2
(-1100 600);
DISPLAY 0.553191 (-1100 600);
DISPLAY INVISIBLE (-1100 600);
FORCEPROP 2 LAST TOLERANCE 20%
J 2
(-1000 600);
DISPLAY 0.553191 (-1000 600);
DISPLAY INVISIBLE (-1000 600);
FORCEPROP 1 LAST PART_NUMBER SP_CH4221MEE01
J 2
(-1041 638);
DISPLAY 0.574468 (-1041 638);
PAINT GREEN (-1041 638);
DISPLAY INVISIBLE (-1041 638);
FORCEPROP 1 LAST PATH I231
J 2
(-925 550);
DISPLAY 0.723404 (-925 550);
DISPLAY INVISIBLE (-925 550);
FORCEADD Q_CAP_DIFFBUS..2
R 2
(-925 600);
FORCEPROP 1 LAST LOCATION C1574
J 2
(-675 625);
DISPLAY 0.723404 (-675 625);
PAINT GREEN (-675 625);
FORCEPROP 2 LAST $SEC 1
J 2
(-750 675);
DISPLAY 0.680851 (-750 675);
PAINT MONO (-750 675);
DISPLAY INVISIBLE (-750 675);
FORCEPROP 2 LAST CDS_SEC 1
J 2
(-750 675);
DISPLAY 0.680851 (-750 675);
DISPLAY INVISIBLE (-750 675);
FORCEPROP 2 LASTPIN (-850 600) $PN 1
J 0
(-840 610);
DISPLAY 0.808511 (-840 610);
FORCEPROP 2 LASTPIN (-1000 600) $PN 2
J 2
(-1010 610);
DISPLAY 0.808511 (-1010 610);
FORCEPROP 2 LAST VALUE DIFF BUS_0.22UF
J 2
(-1075 600);
DISPLAY 0.553191 (-1075 600);
FORCEPROP 1 LAST PIN_NAMES_ROTATE TRUE
J 2
(-925 600);
DISPLAY 0.489362 (-925 600);
PAINT GREEN (-925 600);
DISPLAY INVISIBLE (-925 600);
FORCEPROP 2 LAST CDS_LIB pure_quanta
J 2
(-925 600);
DISPLAY INVISIBLE (-925 600);
FORCEPROP 1 LAST CDS_LMAN_SYM_OUTLINE -25,50,25,-50
J 2
(-925 600);
DISPLAY 0.468085 (-925 600);
PAINT GREEN (-925 600);
DISPLAY INVISIBLE (-925 600);
FORCEPROP 2 LAST VOLTAGE 6.3V
J 2
(-1275 650);
DISPLAY 0.553191 (-1275 650);
DISPLAY INVISIBLE (-1275 650);
FORCEPROP 1 LAST MATERIAL X6S
J 2
(-916 679);
DISPLAY 0.574468 (-916 679);
PAINT GREEN (-916 679);
DISPLAY INVISIBLE (-916 679);
FORCEPROP 2 LAST PACK_TYPE C0201
J 2
(-1100 650);
DISPLAY 0.553191 (-1100 650);
DISPLAY INVISIBLE (-1100 650);
FORCEPROP 2 LAST TOLERANCE 20%
J 2
(-1000 650);
DISPLAY 0.553191 (-1000 650);
DISPLAY INVISIBLE (-1000 650);
FORCEPROP 1 LAST PART_NUMBER SP_CH4221MEE01
J 2
(-1041 688);
DISPLAY 0.574468 (-1041 688);
PAINT GREEN (-1041 688);
DISPLAY INVISIBLE (-1041 688);
FORCEPROP 1 LAST PATH I232
J 2
(-925 600);
DISPLAY 0.723404 (-925 600);
DISPLAY INVISIBLE (-925 600);
FORCEADD Q_CAP_DIFFBUS..2
R 2
(-925 750);
FORCEPROP 1 LAST LOCATION C1573
J 2
(-675 775);
DISPLAY 0.723404 (-675 775);
PAINT GREEN (-675 775);
FORCEPROP 2 LAST $SEC 1
J 2
(-750 825);
DISPLAY 0.680851 (-750 825);
PAINT MONO (-750 825);
DISPLAY INVISIBLE (-750 825);
FORCEPROP 2 LAST CDS_SEC 1
J 2
(-750 825);
DISPLAY 0.680851 (-750 825);
DISPLAY INVISIBLE (-750 825);
FORCEPROP 2 LASTPIN (-850 750) $PN 1
J 0
(-840 760);
DISPLAY 0.808511 (-840 760);
FORCEPROP 2 LASTPIN (-1000 750) $PN 2
J 2
(-1010 760);
DISPLAY 0.808511 (-1010 760);
FORCEPROP 2 LAST VALUE DIFF BUS_0.22UF
J 2
(-1075 750);
DISPLAY 0.553191 (-1075 750);
FORCEPROP 1 LAST PIN_NAMES_ROTATE TRUE
J 2
(-925 750);
DISPLAY 0.489362 (-925 750);
PAINT GREEN (-925 750);
DISPLAY INVISIBLE (-925 750);
FORCEPROP 1 LAST CDS_LMAN_SYM_OUTLINE -25,50,25,-50
J 2
(-925 750);
DISPLAY 0.468085 (-925 750);
PAINT GREEN (-925 750);
DISPLAY INVISIBLE (-925 750);
FORCEPROP 2 LAST CDS_LIB pure_quanta
J 2
(-925 750);
DISPLAY INVISIBLE (-925 750);
FORCEPROP 2 LAST VOLTAGE 6.3V
J 2
(-1275 800);
DISPLAY 0.553191 (-1275 800);
DISPLAY INVISIBLE (-1275 800);
FORCEPROP 1 LAST MATERIAL X6S
J 2
(-916 829);
DISPLAY 0.574468 (-916 829);
PAINT GREEN (-916 829);
DISPLAY INVISIBLE (-916 829);
FORCEPROP 2 LAST PACK_TYPE C0201
J 2
(-1100 800);
DISPLAY 0.553191 (-1100 800);
DISPLAY INVISIBLE (-1100 800);
FORCEPROP 2 LAST TOLERANCE 20%
J 2
(-1000 800);
DISPLAY 0.553191 (-1000 800);
DISPLAY INVISIBLE (-1000 800);
FORCEPROP 1 LAST PART_NUMBER SP_CH4221MEE01
J 2
(-1041 838);
DISPLAY 0.574468 (-1041 838);
PAINT GREEN (-1041 838);
DISPLAY INVISIBLE (-1041 838);
FORCEPROP 1 LAST PATH I233
J 2
(-925 750);
DISPLAY 0.723404 (-925 750);
DISPLAY INVISIBLE (-925 750);
FORCEADD Q_CAP_DIFFBUS..2
R 2
(-925 800);
FORCEPROP 1 LAST LOCATION C1572
J 2
(-675 825);
DISPLAY 0.723404 (-675 825);
PAINT GREEN (-675 825);
FORCEPROP 2 LAST $SEC 1
J 2
(-750 875);
DISPLAY 0.680851 (-750 875);
PAINT MONO (-750 875);
DISPLAY INVISIBLE (-750 875);
FORCEPROP 2 LAST CDS_SEC 1
J 2
(-750 875);
DISPLAY 0.680851 (-750 875);
DISPLAY INVISIBLE (-750 875);
FORCEPROP 2 LASTPIN (-850 800) $PN 1
J 0
(-840 810);
DISPLAY 0.808511 (-840 810);
FORCEPROP 2 LASTPIN (-1000 800) $PN 2
J 2
(-1010 810);
DISPLAY 0.808511 (-1010 810);
FORCEPROP 2 LAST VALUE DIFF BUS_0.22UF
J 2
(-1075 800);
DISPLAY 0.553191 (-1075 800);
FORCEPROP 1 LAST PIN_NAMES_ROTATE TRUE
J 2
(-925 800);
DISPLAY 0.489362 (-925 800);
PAINT GREEN (-925 800);
DISPLAY INVISIBLE (-925 800);
FORCEPROP 1 LAST CDS_LMAN_SYM_OUTLINE -25,50,25,-50
J 2
(-925 800);
DISPLAY 0.468085 (-925 800);
PAINT GREEN (-925 800);
DISPLAY INVISIBLE (-925 800);
FORCEPROP 2 LAST CDS_LIB pure_quanta
J 2
(-925 800);
DISPLAY INVISIBLE (-925 800);
FORCEPROP 2 LAST VOLTAGE 6.3V
J 2
(-1275 850);
DISPLAY 0.553191 (-1275 850);
DISPLAY INVISIBLE (-1275 850);
FORCEPROP 1 LAST MATERIAL X6S
J 2
(-916 879);
DISPLAY 0.574468 (-916 879);
PAINT GREEN (-916 879);
DISPLAY INVISIBLE (-916 879);
FORCEPROP 2 LAST PACK_TYPE C0201
J 2
(-1100 850);
DISPLAY 0.553191 (-1100 850);
DISPLAY INVISIBLE (-1100 850);
FORCEPROP 2 LAST TOLERANCE 20%
J 2
(-1000 850);
DISPLAY 0.553191 (-1000 850);
DISPLAY INVISIBLE (-1000 850);
FORCEPROP 1 LAST PART_NUMBER SP_CH4221MEE01
J 2
(-1041 888);
DISPLAY 0.574468 (-1041 888);
PAINT GREEN (-1041 888);
DISPLAY INVISIBLE (-1041 888);
FORCEPROP 1 LAST PATH I234
J 2
(-925 800);
DISPLAY 0.723404 (-925 800);
DISPLAY INVISIBLE (-925 800);
FORCEADD Q_CAP_DIFFBUS..2
R 2
(-925 1000);
FORCEPROP 1 LAST LOCATION C1570
J 2
(-675 1025);
DISPLAY 0.723404 (-675 1025);
PAINT GREEN (-675 1025);
FORCEPROP 2 LAST $SEC 1
J 2
(-750 1075);
DISPLAY 0.680851 (-750 1075);
PAINT MONO (-750 1075);
DISPLAY INVISIBLE (-750 1075);
FORCEPROP 2 LAST CDS_SEC 1
J 2
(-750 1075);
DISPLAY 0.680851 (-750 1075);
DISPLAY INVISIBLE (-750 1075);
FORCEPROP 2 LASTPIN (-850 1000) $PN 1
J 0
(-840 1010);
DISPLAY 0.808511 (-840 1010);
FORCEPROP 2 LASTPIN (-1000 1000) $PN 2
J 2
(-1010 1010);
DISPLAY 0.808511 (-1010 1010);
FORCEPROP 2 LAST VALUE DIFF BUS_0.22UF
J 2
(-1075 1000);
DISPLAY 0.553191 (-1075 1000);
FORCEPROP 1 LAST PIN_NAMES_ROTATE TRUE
J 2
(-925 1000);
DISPLAY 0.489362 (-925 1000);
PAINT GREEN (-925 1000);
DISPLAY INVISIBLE (-925 1000);
FORCEPROP 2 LAST CDS_LIB pure_quanta
J 2
(-925 1000);
DISPLAY INVISIBLE (-925 1000);
FORCEPROP 1 LAST CDS_LMAN_SYM_OUTLINE -25,50,25,-50
J 2
(-925 1000);
DISPLAY 0.468085 (-925 1000);
PAINT GREEN (-925 1000);
DISPLAY INVISIBLE (-925 1000);
FORCEPROP 2 LAST VOLTAGE 6.3V
J 2
(-1275 1050);
DISPLAY 0.553191 (-1275 1050);
DISPLAY INVISIBLE (-1275 1050);
FORCEPROP 1 LAST MATERIAL X6S
J 2
(-916 1079);
DISPLAY 0.574468 (-916 1079);
PAINT GREEN (-916 1079);
DISPLAY INVISIBLE (-916 1079);
FORCEPROP 2 LAST PACK_TYPE C0201
J 2
(-1100 1050);
DISPLAY 0.553191 (-1100 1050);
DISPLAY INVISIBLE (-1100 1050);
FORCEPROP 2 LAST TOLERANCE 20%
J 2
(-1000 1050);
DISPLAY 0.553191 (-1000 1050);
DISPLAY INVISIBLE (-1000 1050);
FORCEPROP 1 LAST PART_NUMBER SP_CH4221MEE01
J 2
(-1041 1088);
DISPLAY 0.574468 (-1041 1088);
PAINT GREEN (-1041 1088);
DISPLAY INVISIBLE (-1041 1088);
FORCEPROP 1 LAST PATH I235
J 2
(-925 1000);
DISPLAY 0.723404 (-925 1000);
DISPLAY INVISIBLE (-925 1000);
FORCEADD Q_CAP_DIFFBUS..2
R 2
(-925 950);
FORCEPROP 1 LAST LOCATION C1571
J 2
(-675 975);
DISPLAY 0.723404 (-675 975);
PAINT GREEN (-675 975);
FORCEPROP 2 LAST $SEC 1
J 2
(-750 1025);
DISPLAY 0.680851 (-750 1025);
PAINT MONO (-750 1025);
DISPLAY INVISIBLE (-750 1025);
FORCEPROP 2 LAST CDS_SEC 1
J 2
(-750 1025);
DISPLAY 0.680851 (-750 1025);
DISPLAY INVISIBLE (-750 1025);
FORCEPROP 2 LASTPIN (-850 950) $PN 1
J 0
(-840 960);
DISPLAY 0.808511 (-840 960);
FORCEPROP 2 LASTPIN (-1000 950) $PN 2
J 2
(-1010 960);
DISPLAY 0.808511 (-1010 960);
FORCEPROP 2 LAST VALUE DIFF BUS_0.22UF
J 2
(-1075 950);
DISPLAY 0.553191 (-1075 950);
FORCEPROP 1 LAST PIN_NAMES_ROTATE TRUE
J 2
(-925 950);
DISPLAY 0.489362 (-925 950);
PAINT GREEN (-925 950);
DISPLAY INVISIBLE (-925 950);
FORCEPROP 2 LAST CDS_LIB pure_quanta
J 2
(-925 950);
DISPLAY INVISIBLE (-925 950);
FORCEPROP 1 LAST CDS_LMAN_SYM_OUTLINE -25,50,25,-50
J 2
(-925 950);
DISPLAY 0.468085 (-925 950);
PAINT GREEN (-925 950);
DISPLAY INVISIBLE (-925 950);
FORCEPROP 2 LAST VOLTAGE 6.3V
J 2
(-1275 1000);
DISPLAY 0.553191 (-1275 1000);
DISPLAY INVISIBLE (-1275 1000);
FORCEPROP 1 LAST MATERIAL X6S
J 2
(-916 1029);
DISPLAY 0.574468 (-916 1029);
PAINT GREEN (-916 1029);
DISPLAY INVISIBLE (-916 1029);
FORCEPROP 2 LAST PACK_TYPE C0201
J 2
(-1100 1000);
DISPLAY 0.553191 (-1100 1000);
DISPLAY INVISIBLE (-1100 1000);
FORCEPROP 2 LAST TOLERANCE 20%
J 2
(-1000 1000);
DISPLAY 0.553191 (-1000 1000);
DISPLAY INVISIBLE (-1000 1000);
FORCEPROP 1 LAST PART_NUMBER SP_CH4221MEE01
J 2
(-1041 1038);
DISPLAY 0.574468 (-1041 1038);
PAINT GREEN (-1041 1038);
DISPLAY INVISIBLE (-1041 1038);
FORCEPROP 1 LAST PATH I236
J 2
(-925 950);
DISPLAY 0.723404 (-925 950);
DISPLAY INVISIBLE (-925 950);
FORCEADD Q_CAP_DIFFBUS..2
R 2
(-925 1150);
FORCEPROP 1 LAST LOCATION C1569
J 2
(-675 1175);
DISPLAY 0.723404 (-675 1175);
PAINT GREEN (-675 1175);
FORCEPROP 2 LAST $SEC 1
J 2
(-750 1225);
DISPLAY 0.680851 (-750 1225);
PAINT MONO (-750 1225);
DISPLAY INVISIBLE (-750 1225);
FORCEPROP 2 LAST CDS_SEC 1
J 2
(-750 1225);
DISPLAY 0.680851 (-750 1225);
DISPLAY INVISIBLE (-750 1225);
FORCEPROP 2 LASTPIN (-850 1150) $PN 1
J 0
(-840 1160);
DISPLAY 0.808511 (-840 1160);
FORCEPROP 2 LASTPIN (-1000 1150) $PN 2
J 2
(-1010 1160);
DISPLAY 0.808511 (-1010 1160);
FORCEPROP 2 LAST VALUE DIFF BUS_0.22UF
J 2
(-1075 1150);
DISPLAY 0.553191 (-1075 1150);
FORCEPROP 1 LAST PIN_NAMES_ROTATE TRUE
J 2
(-925 1150);
DISPLAY 0.489362 (-925 1150);
PAINT GREEN (-925 1150);
DISPLAY INVISIBLE (-925 1150);
FORCEPROP 2 LAST CDS_LIB pure_quanta
J 2
(-925 1150);
DISPLAY INVISIBLE (-925 1150);
FORCEPROP 1 LAST CDS_LMAN_SYM_OUTLINE -25,50,25,-50
J 2
(-925 1150);
DISPLAY 0.468085 (-925 1150);
PAINT GREEN (-925 1150);
DISPLAY INVISIBLE (-925 1150);
FORCEPROP 2 LAST VOLTAGE 6.3V
J 2
(-1275 1200);
DISPLAY 0.553191 (-1275 1200);
DISPLAY INVISIBLE (-1275 1200);
FORCEPROP 1 LAST MATERIAL X6S
J 2
(-916 1229);
DISPLAY 0.574468 (-916 1229);
PAINT GREEN (-916 1229);
DISPLAY INVISIBLE (-916 1229);
FORCEPROP 2 LAST PACK_TYPE C0201
J 2
(-1100 1200);
DISPLAY 0.553191 (-1100 1200);
DISPLAY INVISIBLE (-1100 1200);
FORCEPROP 2 LAST TOLERANCE 20%
J 2
(-1000 1200);
DISPLAY 0.553191 (-1000 1200);
DISPLAY INVISIBLE (-1000 1200);
FORCEPROP 1 LAST PART_NUMBER SP_CH4221MEE01
J 2
(-1041 1238);
DISPLAY 0.574468 (-1041 1238);
PAINT GREEN (-1041 1238);
DISPLAY INVISIBLE (-1041 1238);
FORCEPROP 1 LAST PATH I237
J 2
(-925 1150);
DISPLAY 0.723404 (-925 1150);
DISPLAY INVISIBLE (-925 1150);
FORCEADD Q_CAP_DIFFBUS..2
R 2
(-925 1200);
FORCEPROP 1 LAST LOCATION C1568
J 2
(-675 1225);
DISPLAY 0.723404 (-675 1225);
PAINT GREEN (-675 1225);
FORCEPROP 2 LAST $SEC 1
J 2
(-750 1275);
DISPLAY 0.680851 (-750 1275);
PAINT MONO (-750 1275);
DISPLAY INVISIBLE (-750 1275);
FORCEPROP 2 LAST CDS_SEC 1
J 2
(-750 1275);
DISPLAY 0.680851 (-750 1275);
DISPLAY INVISIBLE (-750 1275);
FORCEPROP 2 LASTPIN (-850 1200) $PN 1
J 0
(-840 1210);
DISPLAY 0.808511 (-840 1210);
FORCEPROP 2 LASTPIN (-1000 1200) $PN 2
J 2
(-1010 1210);
DISPLAY 0.808511 (-1010 1210);
FORCEPROP 2 LAST VALUE DIFF BUS_0.22UF
J 2
(-1075 1200);
DISPLAY 0.553191 (-1075 1200);
FORCEPROP 1 LAST PIN_NAMES_ROTATE TRUE
J 2
(-925 1200);
DISPLAY 0.489362 (-925 1200);
PAINT GREEN (-925 1200);
DISPLAY INVISIBLE (-925 1200);
FORCEPROP 2 LAST CDS_LIB pure_quanta
J 2
(-925 1200);
DISPLAY INVISIBLE (-925 1200);
FORCEPROP 1 LAST CDS_LMAN_SYM_OUTLINE -25,50,25,-50
J 2
(-925 1200);
DISPLAY 0.468085 (-925 1200);
PAINT GREEN (-925 1200);
DISPLAY INVISIBLE (-925 1200);
FORCEPROP 2 LAST VOLTAGE 6.3V
J 2
(-1275 1250);
DISPLAY 0.553191 (-1275 1250);
DISPLAY INVISIBLE (-1275 1250);
FORCEPROP 1 LAST MATERIAL X6S
J 2
(-916 1279);
DISPLAY 0.574468 (-916 1279);
PAINT GREEN (-916 1279);
DISPLAY INVISIBLE (-916 1279);
FORCEPROP 2 LAST PACK_TYPE C0201
J 2
(-1100 1250);
DISPLAY 0.553191 (-1100 1250);
DISPLAY INVISIBLE (-1100 1250);
FORCEPROP 2 LAST TOLERANCE 20%
J 2
(-1000 1250);
DISPLAY 0.553191 (-1000 1250);
DISPLAY INVISIBLE (-1000 1250);
FORCEPROP 1 LAST PART_NUMBER SP_CH4221MEE01
J 2
(-1041 1288);
DISPLAY 0.574468 (-1041 1288);
PAINT GREEN (-1041 1288);
DISPLAY INVISIBLE (-1041 1288);
FORCEPROP 1 LAST PATH I238
J 2
(-925 1200);
DISPLAY 0.723404 (-925 1200);
DISPLAY INVISIBLE (-925 1200);
FORCEADD Q_CAP_DIFFBUS..2
R 2
(-925 1350);
FORCEPROP 1 LAST LOCATION C47
J 2
(-675 1375);
DISPLAY 0.723404 (-675 1375);
PAINT GREEN (-675 1375);
FORCEPROP 2 LAST $SEC 1
J 2
(-750 1425);
DISPLAY 0.680851 (-750 1425);
PAINT MONO (-750 1425);
DISPLAY INVISIBLE (-750 1425);
FORCEPROP 2 LAST CDS_SEC 1
J 2
(-750 1425);
DISPLAY 0.680851 (-750 1425);
DISPLAY INVISIBLE (-750 1425);
FORCEPROP 2 LASTPIN (-850 1350) $PN 1
J 0
(-840 1360);
DISPLAY 0.808511 (-840 1360);
FORCEPROP 2 LASTPIN (-1000 1350) $PN 2
J 2
(-1010 1360);
DISPLAY 0.808511 (-1010 1360);
FORCEPROP 2 LAST VALUE DIFF BUS_0.22UF
J 2
(-1075 1350);
DISPLAY 0.553191 (-1075 1350);
FORCEPROP 1 LAST PIN_NAMES_ROTATE TRUE
J 2
(-925 1350);
DISPLAY 0.489362 (-925 1350);
PAINT GREEN (-925 1350);
DISPLAY INVISIBLE (-925 1350);
FORCEPROP 2 LAST CDS_LIB pure_quanta
J 2
(-925 1350);
DISPLAY INVISIBLE (-925 1350);
FORCEPROP 1 LAST CDS_LMAN_SYM_OUTLINE -25,50,25,-50
J 2
(-925 1350);
DISPLAY 0.468085 (-925 1350);
PAINT GREEN (-925 1350);
DISPLAY INVISIBLE (-925 1350);
FORCEPROP 2 LAST VOLTAGE 6.3V
J 2
(-1275 1400);
DISPLAY 0.553191 (-1275 1400);
DISPLAY INVISIBLE (-1275 1400);
FORCEPROP 1 LAST MATERIAL X6S
J 2
(-916 1429);
DISPLAY 0.574468 (-916 1429);
PAINT GREEN (-916 1429);
DISPLAY INVISIBLE (-916 1429);
FORCEPROP 2 LAST PACK_TYPE C0201
J 2
(-1100 1400);
DISPLAY 0.553191 (-1100 1400);
DISPLAY INVISIBLE (-1100 1400);
FORCEPROP 2 LAST TOLERANCE 20%
J 2
(-1000 1400);
DISPLAY 0.553191 (-1000 1400);
DISPLAY INVISIBLE (-1000 1400);
FORCEPROP 1 LAST PART_NUMBER SP_CH4221MEE01
J 2
(-1041 1438);
DISPLAY 0.574468 (-1041 1438);
PAINT GREEN (-1041 1438);
DISPLAY INVISIBLE (-1041 1438);
FORCEPROP 1 LAST PATH I239
J 2
(-925 1350);
DISPLAY 0.723404 (-925 1350);
DISPLAY INVISIBLE (-925 1350);
FORCEADD Q_CAP_DIFFBUS..2
R 2
(-925 1400);
FORCEPROP 1 LAST LOCATION C1566
J 2
(-675 1425);
DISPLAY 0.723404 (-675 1425);
PAINT GREEN (-675 1425);
FORCEPROP 2 LAST $SEC 1
J 2
(-750 1475);
DISPLAY 0.680851 (-750 1475);
PAINT MONO (-750 1475);
DISPLAY INVISIBLE (-750 1475);
FORCEPROP 2 LAST CDS_SEC 1
J 2
(-750 1475);
DISPLAY 0.680851 (-750 1475);
DISPLAY INVISIBLE (-750 1475);
FORCEPROP 2 LASTPIN (-850 1400) $PN 1
J 0
(-840 1410);
DISPLAY 0.808511 (-840 1410);
FORCEPROP 2 LASTPIN (-1000 1400) $PN 2
J 2
(-1010 1410);
DISPLAY 0.808511 (-1010 1410);
FORCEPROP 2 LAST VALUE DIFF BUS_0.22UF
J 2
(-1075 1400);
DISPLAY 0.553191 (-1075 1400);
FORCEPROP 1 LAST PIN_NAMES_ROTATE TRUE
J 2
(-925 1400);
DISPLAY 0.489362 (-925 1400);
PAINT GREEN (-925 1400);
DISPLAY INVISIBLE (-925 1400);
FORCEPROP 2 LAST CDS_LIB pure_quanta
J 2
(-925 1400);
DISPLAY INVISIBLE (-925 1400);
FORCEPROP 1 LAST CDS_LMAN_SYM_OUTLINE -25,50,25,-50
J 2
(-925 1400);
DISPLAY 0.468085 (-925 1400);
PAINT GREEN (-925 1400);
DISPLAY INVISIBLE (-925 1400);
FORCEPROP 2 LAST VOLTAGE 6.3V
J 2
(-1275 1450);
DISPLAY 0.553191 (-1275 1450);
DISPLAY INVISIBLE (-1275 1450);
FORCEPROP 1 LAST MATERIAL X6S
J 2
(-916 1479);
DISPLAY 0.574468 (-916 1479);
PAINT GREEN (-916 1479);
DISPLAY INVISIBLE (-916 1479);
FORCEPROP 2 LAST PACK_TYPE C0201
J 2
(-1100 1450);
DISPLAY 0.553191 (-1100 1450);
DISPLAY INVISIBLE (-1100 1450);
FORCEPROP 2 LAST TOLERANCE 20%
J 2
(-1000 1450);
DISPLAY 0.553191 (-1000 1450);
DISPLAY INVISIBLE (-1000 1450);
FORCEPROP 1 LAST PART_NUMBER SP_CH4221MEE01
J 2
(-1041 1488);
DISPLAY 0.574468 (-1041 1488);
PAINT GREEN (-1041 1488);
DISPLAY INVISIBLE (-1041 1488);
FORCEPROP 1 LAST PATH I240
J 2
(-925 1400);
DISPLAY 0.723404 (-925 1400);
DISPLAY INVISIBLE (-925 1400);
FORCEADD Q_CAP_DIFFBUS..2
R 2
(-925 1550);
FORCEPROP 1 LAST LOCATION C1565
J 2
(-675 1575);
DISPLAY 0.723404 (-675 1575);
PAINT GREEN (-675 1575);
FORCEPROP 2 LAST $SEC 1
J 2
(-750 1625);
DISPLAY 0.680851 (-750 1625);
PAINT MONO (-750 1625);
DISPLAY INVISIBLE (-750 1625);
FORCEPROP 2 LAST CDS_SEC 1
J 2
(-750 1625);
DISPLAY 0.680851 (-750 1625);
DISPLAY INVISIBLE (-750 1625);
FORCEPROP 2 LASTPIN (-850 1550) $PN 1
J 0
(-840 1560);
DISPLAY 0.808511 (-840 1560);
FORCEPROP 2 LASTPIN (-1000 1550) $PN 2
J 2
(-1010 1560);
DISPLAY 0.808511 (-1010 1560);
FORCEPROP 2 LAST VALUE DIFF BUS_0.22UF
J 2
(-1075 1550);
DISPLAY 0.553191 (-1075 1550);
FORCEPROP 1 LAST PIN_NAMES_ROTATE TRUE
J 2
(-925 1550);
DISPLAY 0.489362 (-925 1550);
PAINT GREEN (-925 1550);
DISPLAY INVISIBLE (-925 1550);
FORCEPROP 2 LAST CDS_LIB pure_quanta
J 2
(-925 1550);
DISPLAY INVISIBLE (-925 1550);
FORCEPROP 1 LAST CDS_LMAN_SYM_OUTLINE -25,50,25,-50
J 2
(-925 1550);
DISPLAY 0.468085 (-925 1550);
PAINT GREEN (-925 1550);
DISPLAY INVISIBLE (-925 1550);
FORCEPROP 2 LAST VOLTAGE 6.3V
J 2
(-1275 1600);
DISPLAY 0.553191 (-1275 1600);
DISPLAY INVISIBLE (-1275 1600);
FORCEPROP 1 LAST MATERIAL X6S
J 2
(-916 1629);
DISPLAY 0.574468 (-916 1629);
PAINT GREEN (-916 1629);
DISPLAY INVISIBLE (-916 1629);
FORCEPROP 2 LAST PACK_TYPE C0201
J 2
(-1100 1600);
DISPLAY 0.553191 (-1100 1600);
DISPLAY INVISIBLE (-1100 1600);
FORCEPROP 2 LAST TOLERANCE 20%
J 2
(-1000 1600);
DISPLAY 0.553191 (-1000 1600);
DISPLAY INVISIBLE (-1000 1600);
FORCEPROP 1 LAST PART_NUMBER SP_CH4221MEE01
J 2
(-1041 1638);
DISPLAY 0.574468 (-1041 1638);
PAINT GREEN (-1041 1638);
DISPLAY INVISIBLE (-1041 1638);
FORCEPROP 1 LAST PATH I241
J 2
(-925 1550);
DISPLAY 0.723404 (-925 1550);
DISPLAY INVISIBLE (-925 1550);
FORCEADD Q_CAP_DIFFBUS..2
R 2
(-925 1600);
FORCEPROP 1 LAST LOCATION C46
J 2
(-675 1625);
DISPLAY 0.723404 (-675 1625);
PAINT GREEN (-675 1625);
FORCEPROP 2 LAST $SEC 1
J 2
(-750 1675);
DISPLAY 0.680851 (-750 1675);
PAINT MONO (-750 1675);
DISPLAY INVISIBLE (-750 1675);
FORCEPROP 2 LAST CDS_SEC 1
J 2
(-750 1675);
DISPLAY 0.680851 (-750 1675);
DISPLAY INVISIBLE (-750 1675);
FORCEPROP 2 LASTPIN (-850 1600) $PN 1
J 0
(-840 1610);
DISPLAY 0.808511 (-840 1610);
FORCEPROP 2 LASTPIN (-1000 1600) $PN 2
J 2
(-1010 1610);
DISPLAY 0.808511 (-1010 1610);
FORCEPROP 2 LAST VALUE DIFF BUS_0.22UF
J 2
(-1075 1600);
DISPLAY 0.553191 (-1075 1600);
FORCEPROP 1 LAST PIN_NAMES_ROTATE TRUE
J 2
(-925 1600);
DISPLAY 0.489362 (-925 1600);
PAINT GREEN (-925 1600);
DISPLAY INVISIBLE (-925 1600);
FORCEPROP 1 LAST CDS_LMAN_SYM_OUTLINE -25,50,25,-50
J 2
(-925 1600);
DISPLAY 0.468085 (-925 1600);
PAINT GREEN (-925 1600);
DISPLAY INVISIBLE (-925 1600);
FORCEPROP 2 LAST CDS_LIB pure_quanta
J 2
(-925 1600);
DISPLAY INVISIBLE (-925 1600);
FORCEPROP 2 LAST VOLTAGE 6.3V
J 2
(-1275 1650);
DISPLAY 0.553191 (-1275 1650);
DISPLAY INVISIBLE (-1275 1650);
FORCEPROP 1 LAST MATERIAL X6S
J 2
(-916 1679);
DISPLAY 0.574468 (-916 1679);
PAINT GREEN (-916 1679);
DISPLAY INVISIBLE (-916 1679);
FORCEPROP 2 LAST PACK_TYPE C0201
J 2
(-1100 1650);
DISPLAY 0.553191 (-1100 1650);
DISPLAY INVISIBLE (-1100 1650);
FORCEPROP 2 LAST TOLERANCE 20%
J 2
(-1000 1650);
DISPLAY 0.553191 (-1000 1650);
DISPLAY INVISIBLE (-1000 1650);
FORCEPROP 1 LAST PART_NUMBER SP_CH4221MEE01
J 2
(-1041 1688);
DISPLAY 0.574468 (-1041 1688);
PAINT GREEN (-1041 1688);
DISPLAY INVISIBLE (-1041 1688);
FORCEPROP 1 LAST PATH I242
J 2
(-925 1600);
DISPLAY 0.723404 (-925 1600);
DISPLAY INVISIBLE (-925 1600);
FORCEADD TAP..1
R 2
(-1900 2125);
FORCEPROP 3 LASTPIN (-1850 2125) SIG_NAME P5E_CPU0_G3_TX_DP<8>
J 0
(-1840 2135);
DISPLAY 0.659574 (-1840 2135);
PAINT MONO (-1840 2135);
DISPLAY INVISIBLE (-1840 2135);
FORCEPROP 1 LASTPIN (-1850 2125) BN 8
J 2
(-1838 2133);
DISPLAY 0.680851 (-1838 2133);
PAINT GREEN (-1838 2133);
FORCEPROP 2 LAST CDS_LIB standard
J 0
(-1900 2125);
DISPLAY INVISIBLE (-1900 2125);
FORCEPROP 1 LAST BODY_TYPE PLUMBING
J 2
(-1900 2175);
DISPLAY 0.872340 (-1900 2175);
PAINT GREEN (-1900 2175);
DISPLAY INVISIBLE (-1900 2175);
FORCEPROP 1 LAST HDL_TAP TRUE
J 2
(-2225 2000);
DISPLAY 0.872340 (-2225 2000);
DISPLAY INVISIBLE (-2225 2000);
FORCEPROP 1 LAST PATH I243
J 2
(-1898 2125);
DISPLAY 0.872340 (-1898 2125);
PAINT GREEN (-1898 2125);
DISPLAY INVISIBLE (-1898 2125);
FORCEADD TAP..1
R 2
(-1900 2325);
FORCEPROP 3 LASTPIN (-1850 2325) SIG_NAME P5E_CPU0_G3_TX_DP<9>
J 0
(-1840 2335);
DISPLAY 0.659574 (-1840 2335);
PAINT MONO (-1840 2335);
DISPLAY INVISIBLE (-1840 2335);
FORCEPROP 1 LASTPIN (-1850 2325) BN 9
J 2
(-1838 2333);
DISPLAY 0.680851 (-1838 2333);
PAINT GREEN (-1838 2333);
FORCEPROP 2 LAST CDS_LIB standard
J 0
(-1900 2325);
DISPLAY INVISIBLE (-1900 2325);
FORCEPROP 1 LAST BODY_TYPE PLUMBING
J 2
(-1900 2375);
DISPLAY 0.872340 (-1900 2375);
PAINT GREEN (-1900 2375);
DISPLAY INVISIBLE (-1900 2375);
FORCEPROP 1 LAST HDL_TAP TRUE
J 2
(-2225 2200);
DISPLAY 0.872340 (-2225 2200);
DISPLAY INVISIBLE (-2225 2200);
FORCEPROP 1 LAST PATH I244
J 2
(-1898 2325);
DISPLAY 0.872340 (-1898 2325);
PAINT GREEN (-1898 2325);
DISPLAY INVISIBLE (-1898 2325);
FORCEADD TAP..1
R 2
(-1900 2525);
FORCEPROP 3 LASTPIN (-1850 2525) SIG_NAME P5E_CPU0_G3_TX_DP<10>
J 0
(-1840 2535);
DISPLAY 0.659574 (-1840 2535);
PAINT MONO (-1840 2535);
DISPLAY INVISIBLE (-1840 2535);
FORCEPROP 1 LASTPIN (-1850 2525) BN 10
J 2
(-1838 2533);
DISPLAY 0.680851 (-1838 2533);
PAINT GREEN (-1838 2533);
FORCEPROP 2 LAST CDS_LIB standard
J 0
(-1900 2525);
DISPLAY INVISIBLE (-1900 2525);
FORCEPROP 1 LAST BODY_TYPE PLUMBING
J 2
(-1900 2575);
DISPLAY 0.872340 (-1900 2575);
PAINT GREEN (-1900 2575);
DISPLAY INVISIBLE (-1900 2575);
FORCEPROP 1 LAST HDL_TAP TRUE
J 2
(-2225 2400);
DISPLAY 0.872340 (-2225 2400);
DISPLAY INVISIBLE (-2225 2400);
FORCEPROP 1 LAST PATH I245
J 2
(-1898 2525);
DISPLAY 0.872340 (-1898 2525);
PAINT GREEN (-1898 2525);
DISPLAY INVISIBLE (-1898 2525);
FORCEADD TAP..1
R 2
(-1650 2175);
FORCEPROP 3 LASTPIN (-1600 2175) SIG_NAME P5E_CPU0_G3_TX_DN<8>
J 0
(-1590 2185);
DISPLAY 0.659574 (-1590 2185);
PAINT MONO (-1590 2185);
DISPLAY INVISIBLE (-1590 2185);
FORCEPROP 1 LASTPIN (-1600 2175) BN 8
J 2
(-1588 2183);
DISPLAY 0.680851 (-1588 2183);
PAINT GREEN (-1588 2183);
FORCEPROP 2 LAST CDS_LIB standard
J 0
(-1650 2175);
DISPLAY INVISIBLE (-1650 2175);
FORCEPROP 1 LAST BODY_TYPE PLUMBING
J 2
(-1650 2225);
DISPLAY 0.872340 (-1650 2225);
PAINT GREEN (-1650 2225);
DISPLAY INVISIBLE (-1650 2225);
FORCEPROP 1 LAST HDL_TAP TRUE
J 2
(-1975 2050);
DISPLAY 0.872340 (-1975 2050);
DISPLAY INVISIBLE (-1975 2050);
FORCEPROP 1 LAST PATH I246
J 2
(-1648 2175);
DISPLAY 0.872340 (-1648 2175);
PAINT GREEN (-1648 2175);
DISPLAY INVISIBLE (-1648 2175);
FORCEADD TAP..1
R 2
(-1650 2375);
FORCEPROP 3 LASTPIN (-1600 2375) SIG_NAME P5E_CPU0_G3_TX_DN<9>
J 0
(-1590 2385);
DISPLAY 0.659574 (-1590 2385);
PAINT MONO (-1590 2385);
DISPLAY INVISIBLE (-1590 2385);
FORCEPROP 1 LASTPIN (-1600 2375) BN 9
J 2
(-1588 2383);
DISPLAY 0.680851 (-1588 2383);
PAINT GREEN (-1588 2383);
FORCEPROP 2 LAST CDS_LIB standard
J 0
(-1650 2375);
DISPLAY INVISIBLE (-1650 2375);
FORCEPROP 1 LAST BODY_TYPE PLUMBING
J 2
(-1650 2425);
DISPLAY 0.872340 (-1650 2425);
PAINT GREEN (-1650 2425);
DISPLAY INVISIBLE (-1650 2425);
FORCEPROP 1 LAST HDL_TAP TRUE
J 2
(-1975 2250);
DISPLAY 0.872340 (-1975 2250);
DISPLAY INVISIBLE (-1975 2250);
FORCEPROP 1 LAST PATH I247
J 2
(-1648 2375);
DISPLAY 0.872340 (-1648 2375);
PAINT GREEN (-1648 2375);
DISPLAY INVISIBLE (-1648 2375);
FORCEADD TAP..1
R 2
(-1900 2725);
FORCEPROP 3 LASTPIN (-1850 2725) SIG_NAME P5E_CPU0_G3_TX_DP<11>
J 0
(-1840 2735);
DISPLAY 0.659574 (-1840 2735);
PAINT MONO (-1840 2735);
DISPLAY INVISIBLE (-1840 2735);
FORCEPROP 1 LASTPIN (-1850 2725) BN 11
J 2
(-1838 2733);
DISPLAY 0.680851 (-1838 2733);
PAINT GREEN (-1838 2733);
FORCEPROP 2 LAST CDS_LIB standard
J 0
(-1900 2725);
DISPLAY INVISIBLE (-1900 2725);
FORCEPROP 1 LAST BODY_TYPE PLUMBING
J 2
(-1900 2775);
DISPLAY 0.872340 (-1900 2775);
PAINT GREEN (-1900 2775);
DISPLAY INVISIBLE (-1900 2775);
FORCEPROP 1 LAST HDL_TAP TRUE
J 2
(-2225 2600);
DISPLAY 0.872340 (-2225 2600);
DISPLAY INVISIBLE (-2225 2600);
FORCEPROP 1 LAST PATH I248
J 2
(-1898 2725);
DISPLAY 0.872340 (-1898 2725);
PAINT GREEN (-1898 2725);
DISPLAY INVISIBLE (-1898 2725);
FORCEADD TAP..1
R 2
(-1900 2925);
FORCEPROP 3 LASTPIN (-1850 2925) SIG_NAME P5E_CPU0_G3_TX_DP<12>
J 0
(-1840 2935);
DISPLAY 0.659574 (-1840 2935);
PAINT MONO (-1840 2935);
DISPLAY INVISIBLE (-1840 2935);
FORCEPROP 1 LASTPIN (-1850 2925) BN 12
J 2
(-1838 2933);
DISPLAY 0.680851 (-1838 2933);
PAINT GREEN (-1838 2933);
FORCEPROP 2 LAST CDS_LIB standard
J 0
(-1900 2925);
DISPLAY INVISIBLE (-1900 2925);
FORCEPROP 1 LAST BODY_TYPE PLUMBING
J 2
(-1900 2975);
DISPLAY 0.872340 (-1900 2975);
PAINT GREEN (-1900 2975);
DISPLAY INVISIBLE (-1900 2975);
FORCEPROP 1 LAST HDL_TAP TRUE
J 2
(-2225 2800);
DISPLAY 0.872340 (-2225 2800);
DISPLAY INVISIBLE (-2225 2800);
FORCEPROP 1 LAST PATH I249
J 2
(-1898 2925);
DISPLAY 0.872340 (-1898 2925);
PAINT GREEN (-1898 2925);
DISPLAY INVISIBLE (-1898 2925);
FORCEADD TAP..1
R 2
(-1650 2775);
FORCEPROP 3 LASTPIN (-1600 2775) SIG_NAME P5E_CPU0_G3_TX_DN<11>
J 0
(-1590 2785);
DISPLAY 0.659574 (-1590 2785);
PAINT MONO (-1590 2785);
DISPLAY INVISIBLE (-1590 2785);
FORCEPROP 1 LASTPIN (-1600 2775) BN 11
J 2
(-1588 2783);
DISPLAY 0.680851 (-1588 2783);
PAINT GREEN (-1588 2783);
FORCEPROP 2 LAST CDS_LIB standard
J 0
(-1650 2775);
DISPLAY INVISIBLE (-1650 2775);
FORCEPROP 1 LAST BODY_TYPE PLUMBING
J 2
(-1650 2825);
DISPLAY 0.872340 (-1650 2825);
PAINT GREEN (-1650 2825);
DISPLAY INVISIBLE (-1650 2825);
FORCEPROP 1 LAST HDL_TAP TRUE
J 2
(-1975 2650);
DISPLAY 0.872340 (-1975 2650);
DISPLAY INVISIBLE (-1975 2650);
FORCEPROP 1 LAST PATH I250
J 2
(-1648 2775);
DISPLAY 0.872340 (-1648 2775);
PAINT GREEN (-1648 2775);
DISPLAY INVISIBLE (-1648 2775);
FORCEADD TAP..1
R 2
(-1650 2575);
FORCEPROP 3 LASTPIN (-1600 2575) SIG_NAME P5E_CPU0_G3_TX_DN<10>
J 0
(-1590 2585);
DISPLAY 0.659574 (-1590 2585);
PAINT MONO (-1590 2585);
DISPLAY INVISIBLE (-1590 2585);
FORCEPROP 1 LASTPIN (-1600 2575) BN 10
J 2
(-1588 2583);
DISPLAY 0.680851 (-1588 2583);
PAINT GREEN (-1588 2583);
FORCEPROP 2 LAST CDS_LIB standard
J 0
(-1650 2575);
DISPLAY INVISIBLE (-1650 2575);
FORCEPROP 1 LAST BODY_TYPE PLUMBING
J 2
(-1650 2625);
DISPLAY 0.872340 (-1650 2625);
PAINT GREEN (-1650 2625);
DISPLAY INVISIBLE (-1650 2625);
FORCEPROP 1 LAST HDL_TAP TRUE
J 2
(-1975 2450);
DISPLAY 0.872340 (-1975 2450);
DISPLAY INVISIBLE (-1975 2450);
FORCEPROP 1 LAST PATH I251
J 2
(-1648 2575);
DISPLAY 0.872340 (-1648 2575);
PAINT GREEN (-1648 2575);
DISPLAY INVISIBLE (-1648 2575);
FORCEADD TAP..1
R 2
(-1650 2975);
FORCEPROP 3 LASTPIN (-1600 2975) SIG_NAME P5E_CPU0_G3_TX_DN<12>
J 0
(-1590 2985);
DISPLAY 0.659574 (-1590 2985);
PAINT MONO (-1590 2985);
DISPLAY INVISIBLE (-1590 2985);
FORCEPROP 1 LASTPIN (-1600 2975) BN 12
J 2
(-1588 2983);
DISPLAY 0.680851 (-1588 2983);
PAINT GREEN (-1588 2983);
FORCEPROP 2 LAST CDS_LIB standard
J 0
(-1650 2975);
DISPLAY INVISIBLE (-1650 2975);
FORCEPROP 1 LAST BODY_TYPE PLUMBING
J 2
(-1650 3025);
DISPLAY 0.872340 (-1650 3025);
PAINT GREEN (-1650 3025);
DISPLAY INVISIBLE (-1650 3025);
FORCEPROP 1 LAST HDL_TAP TRUE
J 2
(-1975 2850);
DISPLAY 0.872340 (-1975 2850);
DISPLAY INVISIBLE (-1975 2850);
FORCEPROP 1 LAST PATH I252
J 2
(-1648 2975);
DISPLAY 0.872340 (-1648 2975);
PAINT GREEN (-1648 2975);
DISPLAY INVISIBLE (-1648 2975);
FORCEADD TAP..1
R 2
(-1900 3325);
FORCEPROP 3 LASTPIN (-1850 3325) SIG_NAME P5E_CPU0_G3_TX_DP<14>
J 0
(-1840 3335);
DISPLAY 0.659574 (-1840 3335);
PAINT MONO (-1840 3335);
DISPLAY INVISIBLE (-1840 3335);
FORCEPROP 1 LASTPIN (-1850 3325) BN 14
J 2
(-1838 3333);
DISPLAY 0.680851 (-1838 3333);
PAINT GREEN (-1838 3333);
FORCEPROP 2 LAST CDS_LIB standard
J 0
(-1900 3325);
DISPLAY INVISIBLE (-1900 3325);
FORCEPROP 1 LAST BODY_TYPE PLUMBING
J 2
(-1900 3375);
DISPLAY 0.872340 (-1900 3375);
PAINT GREEN (-1900 3375);
DISPLAY INVISIBLE (-1900 3375);
FORCEPROP 1 LAST HDL_TAP TRUE
J 2
(-2225 3200);
DISPLAY 0.872340 (-2225 3200);
DISPLAY INVISIBLE (-2225 3200);
FORCEPROP 1 LAST PATH I253
J 2
(-1898 3325);
DISPLAY 0.872340 (-1898 3325);
PAINT GREEN (-1898 3325);
DISPLAY INVISIBLE (-1898 3325);
FORCEADD TAP..1
R 2
(-1900 3125);
FORCEPROP 3 LASTPIN (-1850 3125) SIG_NAME P5E_CPU0_G3_TX_DP<13>
J 0
(-1840 3135);
DISPLAY 0.659574 (-1840 3135);
PAINT MONO (-1840 3135);
DISPLAY INVISIBLE (-1840 3135);
FORCEPROP 1 LASTPIN (-1850 3125) BN 13
J 2
(-1838 3133);
DISPLAY 0.680851 (-1838 3133);
PAINT GREEN (-1838 3133);
FORCEPROP 2 LAST CDS_LIB standard
J 0
(-1900 3125);
DISPLAY INVISIBLE (-1900 3125);
FORCEPROP 1 LAST BODY_TYPE PLUMBING
J 2
(-1900 3175);
DISPLAY 0.872340 (-1900 3175);
PAINT GREEN (-1900 3175);
DISPLAY INVISIBLE (-1900 3175);
FORCEPROP 1 LAST HDL_TAP TRUE
J 2
(-2225 3000);
DISPLAY 0.872340 (-2225 3000);
DISPLAY INVISIBLE (-2225 3000);
FORCEPROP 1 LAST PATH I254
J 2
(-1898 3125);
DISPLAY 0.872340 (-1898 3125);
PAINT GREEN (-1898 3125);
DISPLAY INVISIBLE (-1898 3125);
FORCEADD TAP..1
R 2
(-1900 3525);
FORCEPROP 3 LASTPIN (-1850 3525) SIG_NAME P5E_CPU0_G3_TX_DP<15>
J 0
(-1840 3535);
DISPLAY 0.659574 (-1840 3535);
PAINT MONO (-1840 3535);
DISPLAY INVISIBLE (-1840 3535);
FORCEPROP 1 LASTPIN (-1850 3525) BN 15
J 2
(-1838 3533);
DISPLAY 0.680851 (-1838 3533);
PAINT GREEN (-1838 3533);
FORCEPROP 2 LAST CDS_LIB standard
J 0
(-1900 3525);
DISPLAY INVISIBLE (-1900 3525);
FORCEPROP 1 LAST BODY_TYPE PLUMBING
J 2
(-1900 3575);
DISPLAY 0.872340 (-1900 3575);
PAINT GREEN (-1900 3575);
DISPLAY INVISIBLE (-1900 3575);
FORCEPROP 1 LAST HDL_TAP TRUE
J 2
(-2225 3400);
DISPLAY 0.872340 (-2225 3400);
DISPLAY INVISIBLE (-2225 3400);
FORCEPROP 1 LAST PATH I255
J 2
(-1898 3525);
DISPLAY 0.872340 (-1898 3525);
PAINT GREEN (-1898 3525);
DISPLAY INVISIBLE (-1898 3525);
FORCEADD TAP..1
R 2
(-1650 3175);
FORCEPROP 3 LASTPIN (-1600 3175) SIG_NAME P5E_CPU0_G3_TX_DN<13>
J 0
(-1590 3185);
DISPLAY 0.659574 (-1590 3185);
PAINT MONO (-1590 3185);
DISPLAY INVISIBLE (-1590 3185);
FORCEPROP 1 LASTPIN (-1600 3175) BN 13
J 2
(-1588 3183);
DISPLAY 0.680851 (-1588 3183);
PAINT GREEN (-1588 3183);
FORCEPROP 2 LAST CDS_LIB standard
J 0
(-1650 3175);
DISPLAY INVISIBLE (-1650 3175);
FORCEPROP 1 LAST BODY_TYPE PLUMBING
J 2
(-1650 3225);
DISPLAY 0.872340 (-1650 3225);
PAINT GREEN (-1650 3225);
DISPLAY INVISIBLE (-1650 3225);
FORCEPROP 1 LAST HDL_TAP TRUE
J 2
(-1975 3050);
DISPLAY 0.872340 (-1975 3050);
DISPLAY INVISIBLE (-1975 3050);
FORCEPROP 1 LAST PATH I256
J 2
(-1648 3175);
DISPLAY 0.872340 (-1648 3175);
PAINT GREEN (-1648 3175);
DISPLAY INVISIBLE (-1648 3175);
FORCEADD TAP..1
R 2
(-1650 3575);
FORCEPROP 3 LASTPIN (-1600 3575) SIG_NAME P5E_CPU0_G3_TX_DN<15>
J 0
(-1590 3585);
DISPLAY 0.659574 (-1590 3585);
PAINT MONO (-1590 3585);
DISPLAY INVISIBLE (-1590 3585);
FORCEPROP 1 LASTPIN (-1600 3575) BN 15
J 2
(-1588 3583);
DISPLAY 0.680851 (-1588 3583);
PAINT GREEN (-1588 3583);
FORCEPROP 2 LAST CDS_LIB standard
J 0
(-1650 3575);
DISPLAY INVISIBLE (-1650 3575);
FORCEPROP 1 LAST BODY_TYPE PLUMBING
J 2
(-1650 3625);
DISPLAY 0.872340 (-1650 3625);
PAINT GREEN (-1650 3625);
DISPLAY INVISIBLE (-1650 3625);
FORCEPROP 1 LAST HDL_TAP TRUE
J 2
(-1975 3450);
DISPLAY 0.872340 (-1975 3450);
DISPLAY INVISIBLE (-1975 3450);
FORCEPROP 1 LAST PATH I257
J 2
(-1648 3575);
DISPLAY 0.872340 (-1648 3575);
PAINT GREEN (-1648 3575);
DISPLAY INVISIBLE (-1648 3575);
FORCEADD TAP..1
R 2
(-1650 3375);
FORCEPROP 3 LASTPIN (-1600 3375) SIG_NAME P5E_CPU0_G3_TX_DN<14>
J 0
(-1590 3385);
DISPLAY 0.659574 (-1590 3385);
PAINT MONO (-1590 3385);
DISPLAY INVISIBLE (-1590 3385);
FORCEPROP 1 LASTPIN (-1600 3375) BN 14
J 2
(-1588 3383);
DISPLAY 0.680851 (-1588 3383);
PAINT GREEN (-1588 3383);
FORCEPROP 2 LAST CDS_LIB standard
J 0
(-1650 3375);
DISPLAY INVISIBLE (-1650 3375);
FORCEPROP 1 LAST BODY_TYPE PLUMBING
J 2
(-1650 3425);
DISPLAY 0.872340 (-1650 3425);
PAINT GREEN (-1650 3425);
DISPLAY INVISIBLE (-1650 3425);
FORCEPROP 1 LAST HDL_TAP TRUE
J 2
(-1975 3250);
DISPLAY 0.872340 (-1975 3250);
DISPLAY INVISIBLE (-1975 3250);
FORCEPROP 1 LAST PATH I258
J 2
(-1648 3375);
DISPLAY 0.872340 (-1648 3375);
PAINT GREEN (-1648 3375);
DISPLAY INVISIBLE (-1648 3375);
FORCEADD Q_CAP_DIFFBUS..2
R 2
(-925 2125);
FORCEPROP 1 LAST LOCATION C44
J 2
(-675 2150);
DISPLAY 0.723404 (-675 2150);
PAINT GREEN (-675 2150);
FORCEPROP 2 LAST $SEC 1
J 2
(-750 2200);
DISPLAY 0.680851 (-750 2200);
PAINT MONO (-750 2200);
DISPLAY INVISIBLE (-750 2200);
FORCEPROP 2 LAST CDS_SEC 1
J 2
(-750 2200);
DISPLAY 0.680851 (-750 2200);
DISPLAY INVISIBLE (-750 2200);
FORCEPROP 2 LASTPIN (-850 2125) $PN 1
J 0
(-840 2135);
DISPLAY 0.808511 (-840 2135);
FORCEPROP 2 LASTPIN (-1000 2125) $PN 2
J 2
(-1010 2135);
DISPLAY 0.808511 (-1010 2135);
FORCEPROP 2 LAST VALUE DIFF BUS_0.22UF
J 2
(-1075 2125);
DISPLAY 0.553191 (-1075 2125);
FORCEPROP 1 LAST CDS_LMAN_SYM_OUTLINE -25,50,25,-50
J 2
(-925 2125);
DISPLAY 0.468085 (-925 2125);
PAINT GREEN (-925 2125);
DISPLAY INVISIBLE (-925 2125);
FORCEPROP 2 LAST CDS_LIB pure_quanta
J 2
(-925 2125);
DISPLAY INVISIBLE (-925 2125);
FORCEPROP 1 LAST PIN_NAMES_ROTATE TRUE
J 2
(-925 2125);
DISPLAY 0.489362 (-925 2125);
PAINT GREEN (-925 2125);
DISPLAY INVISIBLE (-925 2125);
FORCEPROP 2 LAST VOLTAGE 6.3V
J 2
(-1275 2175);
DISPLAY 0.553191 (-1275 2175);
DISPLAY INVISIBLE (-1275 2175);
FORCEPROP 1 LAST MATERIAL X6S
J 2
(-916 2204);
DISPLAY 0.574468 (-916 2204);
PAINT GREEN (-916 2204);
DISPLAY INVISIBLE (-916 2204);
FORCEPROP 2 LAST PACK_TYPE C0201
J 2
(-1100 2175);
DISPLAY 0.553191 (-1100 2175);
DISPLAY INVISIBLE (-1100 2175);
FORCEPROP 2 LAST TOLERANCE 20%
J 2
(-1000 2175);
DISPLAY 0.553191 (-1000 2175);
DISPLAY INVISIBLE (-1000 2175);
FORCEPROP 1 LAST PART_NUMBER SP_CH4221MEE01
J 2
(-1041 2213);
DISPLAY 0.574468 (-1041 2213);
PAINT GREEN (-1041 2213);
DISPLAY INVISIBLE (-1041 2213);
FORCEPROP 1 LAST PATH I259
J 2
(-925 2125);
DISPLAY 0.723404 (-925 2125);
DISPLAY INVISIBLE (-925 2125);
FORCEADD Q_CAP_DIFFBUS..2
R 2
(-925 2175);
FORCEPROP 1 LAST LOCATION C1794
J 2
(-675 2200);
DISPLAY 0.723404 (-675 2200);
PAINT GREEN (-675 2200);
FORCEPROP 2 LAST $SEC 1
J 2
(-750 2250);
DISPLAY 0.680851 (-750 2250);
PAINT MONO (-750 2250);
DISPLAY INVISIBLE (-750 2250);
FORCEPROP 2 LAST CDS_SEC 1
J 2
(-750 2250);
DISPLAY 0.680851 (-750 2250);
DISPLAY INVISIBLE (-750 2250);
FORCEPROP 2 LASTPIN (-850 2175) $PN 1
J 0
(-840 2185);
DISPLAY 0.808511 (-840 2185);
FORCEPROP 2 LASTPIN (-1000 2175) $PN 2
J 2
(-1010 2185);
DISPLAY 0.808511 (-1010 2185);
FORCEPROP 2 LAST VALUE DIFF BUS_0.22UF
J 2
(-1075 2175);
DISPLAY 0.553191 (-1075 2175);
FORCEPROP 1 LAST CDS_LMAN_SYM_OUTLINE -25,50,25,-50
J 2
(-925 2175);
DISPLAY 0.468085 (-925 2175);
PAINT GREEN (-925 2175);
DISPLAY INVISIBLE (-925 2175);
FORCEPROP 2 LAST CDS_LIB pure_quanta
J 2
(-925 2175);
DISPLAY INVISIBLE (-925 2175);
FORCEPROP 1 LAST PIN_NAMES_ROTATE TRUE
J 2
(-925 2175);
DISPLAY 0.489362 (-925 2175);
PAINT GREEN (-925 2175);
DISPLAY INVISIBLE (-925 2175);
FORCEPROP 2 LAST VOLTAGE 6.3V
J 2
(-1275 2225);
DISPLAY 0.553191 (-1275 2225);
DISPLAY INVISIBLE (-1275 2225);
FORCEPROP 1 LAST MATERIAL X6S
J 2
(-916 2254);
DISPLAY 0.574468 (-916 2254);
PAINT GREEN (-916 2254);
DISPLAY INVISIBLE (-916 2254);
FORCEPROP 2 LAST PACK_TYPE C0201
J 2
(-1100 2225);
DISPLAY 0.553191 (-1100 2225);
DISPLAY INVISIBLE (-1100 2225);
FORCEPROP 2 LAST TOLERANCE 20%
J 2
(-1000 2225);
DISPLAY 0.553191 (-1000 2225);
DISPLAY INVISIBLE (-1000 2225);
FORCEPROP 1 LAST PART_NUMBER SP_CH4221MEE01
J 2
(-1041 2263);
DISPLAY 0.574468 (-1041 2263);
PAINT GREEN (-1041 2263);
DISPLAY INVISIBLE (-1041 2263);
FORCEPROP 1 LAST PATH I260
J 2
(-925 2175);
DISPLAY 0.723404 (-925 2175);
DISPLAY INVISIBLE (-925 2175);
FORCEADD Q_CAP_DIFFBUS..2
R 2
(-925 2325);
FORCEPROP 1 LAST LOCATION C1793
J 2
(-675 2350);
DISPLAY 0.723404 (-675 2350);
PAINT GREEN (-675 2350);
FORCEPROP 2 LAST $SEC 1
J 2
(-750 2400);
DISPLAY 0.680851 (-750 2400);
PAINT MONO (-750 2400);
DISPLAY INVISIBLE (-750 2400);
FORCEPROP 2 LAST CDS_SEC 1
J 2
(-750 2400);
DISPLAY 0.680851 (-750 2400);
DISPLAY INVISIBLE (-750 2400);
FORCEPROP 2 LASTPIN (-850 2325) $PN 1
J 0
(-840 2335);
DISPLAY 0.808511 (-840 2335);
FORCEPROP 2 LASTPIN (-1000 2325) $PN 2
J 2
(-1010 2335);
DISPLAY 0.808511 (-1010 2335);
FORCEPROP 2 LAST VALUE DIFF BUS_0.22UF
J 2
(-1075 2325);
DISPLAY 0.553191 (-1075 2325);
FORCEPROP 1 LAST CDS_LMAN_SYM_OUTLINE -25,50,25,-50
J 2
(-925 2325);
DISPLAY 0.468085 (-925 2325);
PAINT GREEN (-925 2325);
DISPLAY INVISIBLE (-925 2325);
FORCEPROP 2 LAST CDS_LIB pure_quanta
J 2
(-925 2325);
DISPLAY INVISIBLE (-925 2325);
FORCEPROP 1 LAST PIN_NAMES_ROTATE TRUE
J 2
(-925 2325);
DISPLAY 0.489362 (-925 2325);
PAINT GREEN (-925 2325);
DISPLAY INVISIBLE (-925 2325);
FORCEPROP 2 LAST VOLTAGE 6.3V
J 2
(-1275 2375);
DISPLAY 0.553191 (-1275 2375);
DISPLAY INVISIBLE (-1275 2375);
FORCEPROP 1 LAST MATERIAL X6S
J 2
(-916 2404);
DISPLAY 0.574468 (-916 2404);
PAINT GREEN (-916 2404);
DISPLAY INVISIBLE (-916 2404);
FORCEPROP 2 LAST PACK_TYPE C0201
J 2
(-1100 2375);
DISPLAY 0.553191 (-1100 2375);
DISPLAY INVISIBLE (-1100 2375);
FORCEPROP 2 LAST TOLERANCE 20%
J 2
(-1000 2375);
DISPLAY 0.553191 (-1000 2375);
DISPLAY INVISIBLE (-1000 2375);
FORCEPROP 1 LAST PART_NUMBER SP_CH4221MEE01
J 2
(-1041 2413);
DISPLAY 0.574468 (-1041 2413);
PAINT GREEN (-1041 2413);
DISPLAY INVISIBLE (-1041 2413);
FORCEPROP 1 LAST PATH I261
J 2
(-925 2325);
DISPLAY 0.723404 (-925 2325);
DISPLAY INVISIBLE (-925 2325);
FORCEADD Q_CAP_DIFFBUS..2
R 2
(-925 2375);
FORCEPROP 1 LAST LOCATION C1560
J 2
(-675 2400);
DISPLAY 0.723404 (-675 2400);
PAINT GREEN (-675 2400);
FORCEPROP 2 LAST $SEC 1
J 2
(-750 2450);
DISPLAY 0.680851 (-750 2450);
PAINT MONO (-750 2450);
DISPLAY INVISIBLE (-750 2450);
FORCEPROP 2 LAST CDS_SEC 1
J 2
(-750 2450);
DISPLAY 0.680851 (-750 2450);
DISPLAY INVISIBLE (-750 2450);
FORCEPROP 2 LASTPIN (-850 2375) $PN 1
J 0
(-840 2385);
DISPLAY 0.808511 (-840 2385);
FORCEPROP 2 LASTPIN (-1000 2375) $PN 2
J 2
(-1010 2385);
DISPLAY 0.808511 (-1010 2385);
FORCEPROP 2 LAST VALUE DIFF BUS_0.22UF
J 2
(-1075 2375);
DISPLAY 0.553191 (-1075 2375);
FORCEPROP 2 LAST CDS_LIB pure_quanta
J 2
(-925 2375);
DISPLAY INVISIBLE (-925 2375);
FORCEPROP 1 LAST CDS_LMAN_SYM_OUTLINE -25,50,25,-50
J 2
(-925 2375);
DISPLAY 0.468085 (-925 2375);
PAINT GREEN (-925 2375);
DISPLAY INVISIBLE (-925 2375);
FORCEPROP 1 LAST PIN_NAMES_ROTATE TRUE
J 2
(-925 2375);
DISPLAY 0.489362 (-925 2375);
PAINT GREEN (-925 2375);
DISPLAY INVISIBLE (-925 2375);
FORCEPROP 2 LAST VOLTAGE 6.3V
J 2
(-1275 2425);
DISPLAY 0.553191 (-1275 2425);
DISPLAY INVISIBLE (-1275 2425);
FORCEPROP 1 LAST MATERIAL X6S
J 2
(-916 2454);
DISPLAY 0.574468 (-916 2454);
PAINT GREEN (-916 2454);
DISPLAY INVISIBLE (-916 2454);
FORCEPROP 2 LAST PACK_TYPE C0201
J 2
(-1100 2425);
DISPLAY 0.553191 (-1100 2425);
DISPLAY INVISIBLE (-1100 2425);
FORCEPROP 2 LAST TOLERANCE 20%
J 2
(-1000 2425);
DISPLAY 0.553191 (-1000 2425);
DISPLAY INVISIBLE (-1000 2425);
FORCEPROP 1 LAST PART_NUMBER SP_CH4221MEE01
J 2
(-1041 2463);
DISPLAY 0.574468 (-1041 2463);
PAINT GREEN (-1041 2463);
DISPLAY INVISIBLE (-1041 2463);
FORCEPROP 1 LAST PATH I262
J 2
(-925 2375);
DISPLAY 0.723404 (-925 2375);
DISPLAY INVISIBLE (-925 2375);
FORCEADD Q_CAP_DIFFBUS..2
R 2
(-925 2525);
FORCEPROP 1 LAST LOCATION C1559
J 2
(-675 2550);
DISPLAY 0.723404 (-675 2550);
PAINT GREEN (-675 2550);
FORCEPROP 2 LAST $SEC 1
J 2
(-750 2600);
DISPLAY 0.680851 (-750 2600);
PAINT MONO (-750 2600);
DISPLAY INVISIBLE (-750 2600);
FORCEPROP 2 LAST CDS_SEC 1
J 2
(-750 2600);
DISPLAY 0.680851 (-750 2600);
DISPLAY INVISIBLE (-750 2600);
FORCEPROP 2 LASTPIN (-850 2525) $PN 1
J 0
(-840 2535);
DISPLAY 0.808511 (-840 2535);
FORCEPROP 2 LASTPIN (-1000 2525) $PN 2
J 2
(-1010 2535);
DISPLAY 0.808511 (-1010 2535);
FORCEPROP 2 LAST VALUE DIFF BUS_0.22UF
J 2
(-1075 2525);
DISPLAY 0.553191 (-1075 2525);
FORCEPROP 1 LAST CDS_LMAN_SYM_OUTLINE -25,50,25,-50
J 2
(-925 2525);
DISPLAY 0.468085 (-925 2525);
PAINT GREEN (-925 2525);
DISPLAY INVISIBLE (-925 2525);
FORCEPROP 2 LAST CDS_LIB pure_quanta
J 2
(-925 2525);
DISPLAY INVISIBLE (-925 2525);
FORCEPROP 1 LAST PIN_NAMES_ROTATE TRUE
J 2
(-925 2525);
DISPLAY 0.489362 (-925 2525);
PAINT GREEN (-925 2525);
DISPLAY INVISIBLE (-925 2525);
FORCEPROP 2 LAST VOLTAGE 6.3V
J 2
(-1275 2575);
DISPLAY 0.553191 (-1275 2575);
DISPLAY INVISIBLE (-1275 2575);
FORCEPROP 1 LAST MATERIAL X6S
J 2
(-916 2604);
DISPLAY 0.574468 (-916 2604);
PAINT GREEN (-916 2604);
DISPLAY INVISIBLE (-916 2604);
FORCEPROP 2 LAST PACK_TYPE C0201
J 2
(-1100 2575);
DISPLAY 0.553191 (-1100 2575);
DISPLAY INVISIBLE (-1100 2575);
FORCEPROP 2 LAST TOLERANCE 20%
J 2
(-1000 2575);
DISPLAY 0.553191 (-1000 2575);
DISPLAY INVISIBLE (-1000 2575);
FORCEPROP 1 LAST PART_NUMBER SP_CH4221MEE01
J 2
(-1041 2613);
DISPLAY 0.574468 (-1041 2613);
PAINT GREEN (-1041 2613);
DISPLAY INVISIBLE (-1041 2613);
FORCEPROP 1 LAST PATH I263
J 2
(-925 2525);
DISPLAY 0.723404 (-925 2525);
DISPLAY INVISIBLE (-925 2525);
FORCEADD Q_CAP_DIFFBUS..2
R 2
(-925 2575);
FORCEPROP 1 LAST LOCATION C1558
J 2
(-675 2600);
DISPLAY 0.723404 (-675 2600);
PAINT GREEN (-675 2600);
FORCEPROP 2 LAST $SEC 1
J 2
(-750 2650);
DISPLAY 0.680851 (-750 2650);
PAINT MONO (-750 2650);
DISPLAY INVISIBLE (-750 2650);
FORCEPROP 2 LAST CDS_SEC 1
J 2
(-750 2650);
DISPLAY 0.680851 (-750 2650);
DISPLAY INVISIBLE (-750 2650);
FORCEPROP 2 LASTPIN (-850 2575) $PN 1
J 0
(-840 2585);
DISPLAY 0.808511 (-840 2585);
FORCEPROP 2 LASTPIN (-1000 2575) $PN 2
J 2
(-1010 2585);
DISPLAY 0.808511 (-1010 2585);
FORCEPROP 2 LAST VALUE DIFF BUS_0.22UF
J 2
(-1075 2575);
DISPLAY 0.553191 (-1075 2575);
FORCEPROP 1 LAST CDS_LMAN_SYM_OUTLINE -25,50,25,-50
J 2
(-925 2575);
DISPLAY 0.468085 (-925 2575);
PAINT GREEN (-925 2575);
DISPLAY INVISIBLE (-925 2575);
FORCEPROP 2 LAST CDS_LIB pure_quanta
J 2
(-925 2575);
DISPLAY INVISIBLE (-925 2575);
FORCEPROP 1 LAST PIN_NAMES_ROTATE TRUE
J 2
(-925 2575);
DISPLAY 0.489362 (-925 2575);
PAINT GREEN (-925 2575);
DISPLAY INVISIBLE (-925 2575);
FORCEPROP 2 LAST VOLTAGE 6.3V
J 2
(-1275 2625);
DISPLAY 0.553191 (-1275 2625);
DISPLAY INVISIBLE (-1275 2625);
FORCEPROP 1 LAST MATERIAL X6S
J 2
(-916 2654);
DISPLAY 0.574468 (-916 2654);
PAINT GREEN (-916 2654);
DISPLAY INVISIBLE (-916 2654);
FORCEPROP 2 LAST PACK_TYPE C0201
J 2
(-1100 2625);
DISPLAY 0.553191 (-1100 2625);
DISPLAY INVISIBLE (-1100 2625);
FORCEPROP 2 LAST TOLERANCE 20%
J 2
(-1000 2625);
DISPLAY 0.553191 (-1000 2625);
DISPLAY INVISIBLE (-1000 2625);
FORCEPROP 1 LAST PART_NUMBER SP_CH4221MEE01
J 2
(-1041 2663);
DISPLAY 0.574468 (-1041 2663);
PAINT GREEN (-1041 2663);
DISPLAY INVISIBLE (-1041 2663);
FORCEPROP 1 LAST PATH I264
J 2
(-925 2575);
DISPLAY 0.723404 (-925 2575);
DISPLAY INVISIBLE (-925 2575);
FORCEADD Q_CAP_DIFFBUS..2
R 2
(-925 2775);
FORCEPROP 1 LAST LOCATION C1556
J 2
(-675 2800);
DISPLAY 0.723404 (-675 2800);
PAINT GREEN (-675 2800);
FORCEPROP 2 LAST $SEC 1
J 2
(-750 2850);
DISPLAY 0.680851 (-750 2850);
PAINT MONO (-750 2850);
DISPLAY INVISIBLE (-750 2850);
FORCEPROP 2 LAST CDS_SEC 1
J 2
(-750 2850);
DISPLAY 0.680851 (-750 2850);
DISPLAY INVISIBLE (-750 2850);
FORCEPROP 2 LASTPIN (-850 2775) $PN 1
J 0
(-840 2785);
DISPLAY 0.808511 (-840 2785);
FORCEPROP 2 LASTPIN (-1000 2775) $PN 2
J 2
(-1010 2785);
DISPLAY 0.808511 (-1010 2785);
FORCEPROP 2 LAST VALUE DIFF BUS_0.22UF
J 2
(-1075 2775);
DISPLAY 0.553191 (-1075 2775);
FORCEPROP 2 LAST CDS_LIB pure_quanta
J 2
(-925 2775);
DISPLAY INVISIBLE (-925 2775);
FORCEPROP 1 LAST CDS_LMAN_SYM_OUTLINE -25,50,25,-50
J 2
(-925 2775);
DISPLAY 0.468085 (-925 2775);
PAINT GREEN (-925 2775);
DISPLAY INVISIBLE (-925 2775);
FORCEPROP 1 LAST PIN_NAMES_ROTATE TRUE
J 2
(-925 2775);
DISPLAY 0.489362 (-925 2775);
PAINT GREEN (-925 2775);
DISPLAY INVISIBLE (-925 2775);
FORCEPROP 2 LAST VOLTAGE 6.3V
J 2
(-1275 2825);
DISPLAY 0.553191 (-1275 2825);
DISPLAY INVISIBLE (-1275 2825);
FORCEPROP 1 LAST MATERIAL X6S
J 2
(-916 2854);
DISPLAY 0.574468 (-916 2854);
PAINT GREEN (-916 2854);
DISPLAY INVISIBLE (-916 2854);
FORCEPROP 2 LAST PACK_TYPE C0201
J 2
(-1100 2825);
DISPLAY 0.553191 (-1100 2825);
DISPLAY INVISIBLE (-1100 2825);
FORCEPROP 2 LAST TOLERANCE 20%
J 2
(-1000 2825);
DISPLAY 0.553191 (-1000 2825);
DISPLAY INVISIBLE (-1000 2825);
FORCEPROP 1 LAST PART_NUMBER SP_CH4221MEE01
J 2
(-1041 2863);
DISPLAY 0.574468 (-1041 2863);
PAINT GREEN (-1041 2863);
DISPLAY INVISIBLE (-1041 2863);
FORCEPROP 1 LAST PATH I265
J 2
(-925 2775);
DISPLAY 0.723404 (-925 2775);
DISPLAY INVISIBLE (-925 2775);
FORCEADD Q_CAP_DIFFBUS..2
R 2
(-925 2725);
FORCEPROP 1 LAST LOCATION C1557
J 2
(-675 2750);
DISPLAY 0.723404 (-675 2750);
PAINT GREEN (-675 2750);
FORCEPROP 2 LAST $SEC 1
J 2
(-750 2800);
DISPLAY 0.680851 (-750 2800);
PAINT MONO (-750 2800);
DISPLAY INVISIBLE (-750 2800);
FORCEPROP 2 LAST CDS_SEC 1
J 2
(-750 2800);
DISPLAY 0.680851 (-750 2800);
DISPLAY INVISIBLE (-750 2800);
FORCEPROP 2 LASTPIN (-850 2725) $PN 1
J 0
(-840 2735);
DISPLAY 0.808511 (-840 2735);
FORCEPROP 2 LASTPIN (-1000 2725) $PN 2
J 2
(-1010 2735);
DISPLAY 0.808511 (-1010 2735);
FORCEPROP 2 LAST VALUE DIFF BUS_0.22UF
J 2
(-1075 2725);
DISPLAY 0.553191 (-1075 2725);
FORCEPROP 2 LAST CDS_LIB pure_quanta
J 2
(-925 2725);
DISPLAY INVISIBLE (-925 2725);
FORCEPROP 1 LAST CDS_LMAN_SYM_OUTLINE -25,50,25,-50
J 2
(-925 2725);
DISPLAY 0.468085 (-925 2725);
PAINT GREEN (-925 2725);
DISPLAY INVISIBLE (-925 2725);
FORCEPROP 1 LAST PIN_NAMES_ROTATE TRUE
J 2
(-925 2725);
DISPLAY 0.489362 (-925 2725);
PAINT GREEN (-925 2725);
DISPLAY INVISIBLE (-925 2725);
FORCEPROP 2 LAST VOLTAGE 6.3V
J 2
(-1275 2775);
DISPLAY 0.553191 (-1275 2775);
DISPLAY INVISIBLE (-1275 2775);
FORCEPROP 1 LAST MATERIAL X6S
J 2
(-916 2804);
DISPLAY 0.574468 (-916 2804);
PAINT GREEN (-916 2804);
DISPLAY INVISIBLE (-916 2804);
FORCEPROP 2 LAST PACK_TYPE C0201
J 2
(-1100 2775);
DISPLAY 0.553191 (-1100 2775);
DISPLAY INVISIBLE (-1100 2775);
FORCEPROP 2 LAST TOLERANCE 20%
J 2
(-1000 2775);
DISPLAY 0.553191 (-1000 2775);
DISPLAY INVISIBLE (-1000 2775);
FORCEPROP 1 LAST PART_NUMBER SP_CH4221MEE01
J 2
(-1041 2813);
DISPLAY 0.574468 (-1041 2813);
PAINT GREEN (-1041 2813);
DISPLAY INVISIBLE (-1041 2813);
FORCEPROP 1 LAST PATH I266
J 2
(-925 2725);
DISPLAY 0.723404 (-925 2725);
DISPLAY INVISIBLE (-925 2725);
FORCEADD Q_CAP_DIFFBUS..2
R 2
(-925 2925);
FORCEPROP 1 LAST LOCATION C1555
J 2
(-675 2950);
DISPLAY 0.723404 (-675 2950);
PAINT GREEN (-675 2950);
FORCEPROP 2 LAST $SEC 1
J 2
(-750 3000);
DISPLAY 0.680851 (-750 3000);
PAINT MONO (-750 3000);
DISPLAY INVISIBLE (-750 3000);
FORCEPROP 2 LAST CDS_SEC 1
J 2
(-750 3000);
DISPLAY 0.680851 (-750 3000);
DISPLAY INVISIBLE (-750 3000);
FORCEPROP 2 LASTPIN (-850 2925) $PN 1
J 0
(-840 2935);
DISPLAY 0.808511 (-840 2935);
FORCEPROP 2 LASTPIN (-1000 2925) $PN 2
J 2
(-1010 2935);
DISPLAY 0.808511 (-1010 2935);
FORCEPROP 2 LAST VALUE DIFF BUS_0.22UF
J 2
(-1075 2925);
DISPLAY 0.553191 (-1075 2925);
FORCEPROP 1 LAST CDS_LMAN_SYM_OUTLINE -25,50,25,-50
J 2
(-925 2925);
DISPLAY 0.468085 (-925 2925);
PAINT GREEN (-925 2925);
DISPLAY INVISIBLE (-925 2925);
FORCEPROP 2 LAST CDS_LIB pure_quanta
J 2
(-925 2925);
DISPLAY INVISIBLE (-925 2925);
FORCEPROP 1 LAST PIN_NAMES_ROTATE TRUE
J 2
(-925 2925);
DISPLAY 0.489362 (-925 2925);
PAINT GREEN (-925 2925);
DISPLAY INVISIBLE (-925 2925);
FORCEPROP 2 LAST VOLTAGE 6.3V
J 2
(-1275 2975);
DISPLAY 0.553191 (-1275 2975);
DISPLAY INVISIBLE (-1275 2975);
FORCEPROP 1 LAST MATERIAL X6S
J 2
(-916 3004);
DISPLAY 0.574468 (-916 3004);
PAINT GREEN (-916 3004);
DISPLAY INVISIBLE (-916 3004);
FORCEPROP 2 LAST PACK_TYPE C0201
J 2
(-1100 2975);
DISPLAY 0.553191 (-1100 2975);
DISPLAY INVISIBLE (-1100 2975);
FORCEPROP 2 LAST TOLERANCE 20%
J 2
(-1000 2975);
DISPLAY 0.553191 (-1000 2975);
DISPLAY INVISIBLE (-1000 2975);
FORCEPROP 1 LAST PART_NUMBER SP_CH4221MEE01
J 2
(-1041 3013);
DISPLAY 0.574468 (-1041 3013);
PAINT GREEN (-1041 3013);
DISPLAY INVISIBLE (-1041 3013);
FORCEPROP 1 LAST PATH I267
J 2
(-925 2925);
DISPLAY 0.723404 (-925 2925);
DISPLAY INVISIBLE (-925 2925);
FORCEADD Q_CAP_DIFFBUS..2
R 2
(-925 2975);
FORCEPROP 1 LAST LOCATION C41
J 2
(-675 3000);
DISPLAY 0.723404 (-675 3000);
PAINT GREEN (-675 3000);
FORCEPROP 2 LAST $SEC 1
J 2
(-750 3050);
DISPLAY 0.680851 (-750 3050);
PAINT MONO (-750 3050);
DISPLAY INVISIBLE (-750 3050);
FORCEPROP 2 LAST CDS_SEC 1
J 2
(-750 3050);
DISPLAY 0.680851 (-750 3050);
DISPLAY INVISIBLE (-750 3050);
FORCEPROP 2 LASTPIN (-850 2975) $PN 1
J 0
(-840 2985);
DISPLAY 0.808511 (-840 2985);
FORCEPROP 2 LASTPIN (-1000 2975) $PN 2
J 2
(-1010 2985);
DISPLAY 0.808511 (-1010 2985);
FORCEPROP 2 LAST VALUE DIFF BUS_0.22UF
J 2
(-1075 2975);
DISPLAY 0.553191 (-1075 2975);
FORCEPROP 1 LAST CDS_LMAN_SYM_OUTLINE -25,50,25,-50
J 2
(-925 2975);
DISPLAY 0.468085 (-925 2975);
PAINT GREEN (-925 2975);
DISPLAY INVISIBLE (-925 2975);
FORCEPROP 2 LAST CDS_LIB pure_quanta
J 2
(-925 2975);
DISPLAY INVISIBLE (-925 2975);
FORCEPROP 1 LAST PIN_NAMES_ROTATE TRUE
J 2
(-925 2975);
DISPLAY 0.489362 (-925 2975);
PAINT GREEN (-925 2975);
DISPLAY INVISIBLE (-925 2975);
FORCEPROP 2 LAST VOLTAGE 6.3V
J 2
(-1275 3025);
DISPLAY 0.553191 (-1275 3025);
DISPLAY INVISIBLE (-1275 3025);
FORCEPROP 1 LAST MATERIAL X6S
J 2
(-916 3054);
DISPLAY 0.574468 (-916 3054);
PAINT GREEN (-916 3054);
DISPLAY INVISIBLE (-916 3054);
FORCEPROP 2 LAST PACK_TYPE C0201
J 2
(-1100 3025);
DISPLAY 0.553191 (-1100 3025);
DISPLAY INVISIBLE (-1100 3025);
FORCEPROP 2 LAST TOLERANCE 20%
J 2
(-1000 3025);
DISPLAY 0.553191 (-1000 3025);
DISPLAY INVISIBLE (-1000 3025);
FORCEPROP 1 LAST PART_NUMBER SP_CH4221MEE01
J 2
(-1041 3063);
DISPLAY 0.574468 (-1041 3063);
PAINT GREEN (-1041 3063);
DISPLAY INVISIBLE (-1041 3063);
FORCEPROP 1 LAST PATH I268
J 2
(-925 2975);
DISPLAY 0.723404 (-925 2975);
DISPLAY INVISIBLE (-925 2975);
FORCEADD Q_CAP_DIFFBUS..2
R 2
(-925 3125);
FORCEPROP 1 LAST LOCATION C1553
J 2
(-675 3150);
DISPLAY 0.723404 (-675 3150);
PAINT GREEN (-675 3150);
FORCEPROP 2 LAST $SEC 1
J 2
(-750 3200);
DISPLAY 0.680851 (-750 3200);
PAINT MONO (-750 3200);
DISPLAY INVISIBLE (-750 3200);
FORCEPROP 2 LAST CDS_SEC 1
J 2
(-750 3200);
DISPLAY 0.680851 (-750 3200);
DISPLAY INVISIBLE (-750 3200);
FORCEPROP 2 LASTPIN (-850 3125) $PN 1
J 0
(-840 3135);
DISPLAY 0.808511 (-840 3135);
FORCEPROP 2 LASTPIN (-1000 3125) $PN 2
J 2
(-1010 3135);
DISPLAY 0.808511 (-1010 3135);
FORCEPROP 2 LAST VALUE DIFF BUS_0.22UF
J 2
(-1075 3125);
DISPLAY 0.553191 (-1075 3125);
FORCEPROP 1 LAST CDS_LMAN_SYM_OUTLINE -25,50,25,-50
J 2
(-925 3125);
DISPLAY 0.468085 (-925 3125);
PAINT GREEN (-925 3125);
DISPLAY INVISIBLE (-925 3125);
FORCEPROP 2 LAST CDS_LIB pure_quanta
J 2
(-925 3125);
DISPLAY INVISIBLE (-925 3125);
FORCEPROP 1 LAST PIN_NAMES_ROTATE TRUE
J 2
(-925 3125);
DISPLAY 0.489362 (-925 3125);
PAINT GREEN (-925 3125);
DISPLAY INVISIBLE (-925 3125);
FORCEPROP 2 LAST VOLTAGE 6.3V
J 2
(-1275 3175);
DISPLAY 0.553191 (-1275 3175);
DISPLAY INVISIBLE (-1275 3175);
FORCEPROP 1 LAST MATERIAL X6S
J 2
(-916 3204);
DISPLAY 0.574468 (-916 3204);
PAINT GREEN (-916 3204);
DISPLAY INVISIBLE (-916 3204);
FORCEPROP 2 LAST PACK_TYPE C0201
J 2
(-1100 3175);
DISPLAY 0.553191 (-1100 3175);
DISPLAY INVISIBLE (-1100 3175);
FORCEPROP 2 LAST TOLERANCE 20%
J 2
(-1000 3175);
DISPLAY 0.553191 (-1000 3175);
DISPLAY INVISIBLE (-1000 3175);
FORCEPROP 1 LAST PART_NUMBER SP_CH4221MEE01
J 2
(-1041 3213);
DISPLAY 0.574468 (-1041 3213);
PAINT GREEN (-1041 3213);
DISPLAY INVISIBLE (-1041 3213);
FORCEPROP 1 LAST PATH I269
J 2
(-925 3125);
DISPLAY 0.723404 (-925 3125);
DISPLAY INVISIBLE (-925 3125);
FORCEADD Q_CAP_DIFFBUS..2
R 2
(-925 3175);
FORCEPROP 1 LAST LOCATION C1552
J 2
(-675 3200);
DISPLAY 0.723404 (-675 3200);
PAINT GREEN (-675 3200);
FORCEPROP 2 LAST $SEC 1
J 2
(-750 3250);
DISPLAY 0.680851 (-750 3250);
PAINT MONO (-750 3250);
DISPLAY INVISIBLE (-750 3250);
FORCEPROP 2 LAST CDS_SEC 1
J 2
(-750 3250);
DISPLAY 0.680851 (-750 3250);
DISPLAY INVISIBLE (-750 3250);
FORCEPROP 2 LASTPIN (-850 3175) $PN 1
J 0
(-840 3185);
DISPLAY 0.808511 (-840 3185);
FORCEPROP 2 LASTPIN (-1000 3175) $PN 2
J 2
(-1010 3185);
DISPLAY 0.808511 (-1010 3185);
FORCEPROP 2 LAST VALUE DIFF BUS_0.22UF
J 2
(-1075 3175);
DISPLAY 0.553191 (-1075 3175);
FORCEPROP 1 LAST CDS_LMAN_SYM_OUTLINE -25,50,25,-50
J 2
(-925 3175);
DISPLAY 0.468085 (-925 3175);
PAINT GREEN (-925 3175);
DISPLAY INVISIBLE (-925 3175);
FORCEPROP 2 LAST CDS_LIB pure_quanta
J 2
(-925 3175);
DISPLAY INVISIBLE (-925 3175);
FORCEPROP 1 LAST PIN_NAMES_ROTATE TRUE
J 2
(-925 3175);
DISPLAY 0.489362 (-925 3175);
PAINT GREEN (-925 3175);
DISPLAY INVISIBLE (-925 3175);
FORCEPROP 2 LAST VOLTAGE 6.3V
J 2
(-1275 3225);
DISPLAY 0.553191 (-1275 3225);
DISPLAY INVISIBLE (-1275 3225);
FORCEPROP 1 LAST MATERIAL X6S
J 2
(-916 3254);
DISPLAY 0.574468 (-916 3254);
PAINT GREEN (-916 3254);
DISPLAY INVISIBLE (-916 3254);
FORCEPROP 2 LAST PACK_TYPE C0201
J 2
(-1100 3225);
DISPLAY 0.553191 (-1100 3225);
DISPLAY INVISIBLE (-1100 3225);
FORCEPROP 2 LAST TOLERANCE 20%
J 2
(-1000 3225);
DISPLAY 0.553191 (-1000 3225);
DISPLAY INVISIBLE (-1000 3225);
FORCEPROP 1 LAST PART_NUMBER SP_CH4221MEE01
J 2
(-1041 3263);
DISPLAY 0.574468 (-1041 3263);
PAINT GREEN (-1041 3263);
DISPLAY INVISIBLE (-1041 3263);
FORCEPROP 1 LAST PATH I270
J 2
(-925 3175);
DISPLAY 0.723404 (-925 3175);
DISPLAY INVISIBLE (-925 3175);
FORCEADD Q_CAP_DIFFBUS..2
R 2
(-925 3325);
FORCEPROP 1 LAST LOCATION C1792
J 2
(-675 3350);
DISPLAY 0.723404 (-675 3350);
PAINT GREEN (-675 3350);
FORCEPROP 2 LAST $SEC 1
J 2
(-750 3400);
DISPLAY 0.680851 (-750 3400);
PAINT MONO (-750 3400);
DISPLAY INVISIBLE (-750 3400);
FORCEPROP 2 LAST CDS_SEC 1
J 2
(-750 3400);
DISPLAY 0.680851 (-750 3400);
DISPLAY INVISIBLE (-750 3400);
FORCEPROP 2 LASTPIN (-850 3325) $PN 1
J 0
(-840 3335);
DISPLAY 0.808511 (-840 3335);
FORCEPROP 2 LASTPIN (-1000 3325) $PN 2
J 2
(-1010 3335);
DISPLAY 0.808511 (-1010 3335);
FORCEPROP 2 LAST VALUE DIFF BUS_0.22UF
J 2
(-1075 3325);
DISPLAY 0.553191 (-1075 3325);
FORCEPROP 1 LAST CDS_LMAN_SYM_OUTLINE -25,50,25,-50
J 2
(-925 3325);
DISPLAY 0.468085 (-925 3325);
PAINT GREEN (-925 3325);
DISPLAY INVISIBLE (-925 3325);
FORCEPROP 2 LAST CDS_LIB pure_quanta
J 2
(-925 3325);
DISPLAY INVISIBLE (-925 3325);
FORCEPROP 1 LAST PIN_NAMES_ROTATE TRUE
J 2
(-925 3325);
DISPLAY 0.489362 (-925 3325);
PAINT GREEN (-925 3325);
DISPLAY INVISIBLE (-925 3325);
FORCEPROP 2 LAST VOLTAGE 6.3V
J 2
(-1275 3375);
DISPLAY 0.553191 (-1275 3375);
DISPLAY INVISIBLE (-1275 3375);
FORCEPROP 1 LAST MATERIAL X6S
J 2
(-916 3404);
DISPLAY 0.574468 (-916 3404);
PAINT GREEN (-916 3404);
DISPLAY INVISIBLE (-916 3404);
FORCEPROP 2 LAST PACK_TYPE C0201
J 2
(-1100 3375);
DISPLAY 0.553191 (-1100 3375);
DISPLAY INVISIBLE (-1100 3375);
FORCEPROP 2 LAST TOLERANCE 20%
J 2
(-1000 3375);
DISPLAY 0.553191 (-1000 3375);
DISPLAY INVISIBLE (-1000 3375);
FORCEPROP 1 LAST PART_NUMBER SP_CH4221MEE01
J 2
(-1041 3413);
DISPLAY 0.574468 (-1041 3413);
PAINT GREEN (-1041 3413);
DISPLAY INVISIBLE (-1041 3413);
FORCEPROP 1 LAST PATH I271
J 2
(-925 3325);
DISPLAY 0.723404 (-925 3325);
DISPLAY INVISIBLE (-925 3325);
FORCEADD Q_CAP_DIFFBUS..2
R 2
(-925 3375);
FORCEPROP 1 LAST LOCATION C1550
J 2
(-675 3400);
DISPLAY 0.723404 (-675 3400);
PAINT GREEN (-675 3400);
FORCEPROP 2 LAST $SEC 1
J 2
(-750 3450);
DISPLAY 0.680851 (-750 3450);
PAINT MONO (-750 3450);
DISPLAY INVISIBLE (-750 3450);
FORCEPROP 2 LAST CDS_SEC 1
J 2
(-750 3450);
DISPLAY 0.680851 (-750 3450);
DISPLAY INVISIBLE (-750 3450);
FORCEPROP 2 LASTPIN (-850 3375) $PN 1
J 0
(-840 3385);
DISPLAY 0.808511 (-840 3385);
FORCEPROP 2 LASTPIN (-1000 3375) $PN 2
J 2
(-1010 3385);
DISPLAY 0.808511 (-1010 3385);
FORCEPROP 2 LAST VALUE DIFF BUS_0.22UF
J 2
(-1075 3375);
DISPLAY 0.553191 (-1075 3375);
FORCEPROP 1 LAST CDS_LMAN_SYM_OUTLINE -25,50,25,-50
J 2
(-925 3375);
DISPLAY 0.468085 (-925 3375);
PAINT GREEN (-925 3375);
DISPLAY INVISIBLE (-925 3375);
FORCEPROP 2 LAST CDS_LIB pure_quanta
J 2
(-925 3375);
DISPLAY INVISIBLE (-925 3375);
FORCEPROP 1 LAST PIN_NAMES_ROTATE TRUE
J 2
(-925 3375);
DISPLAY 0.489362 (-925 3375);
PAINT GREEN (-925 3375);
DISPLAY INVISIBLE (-925 3375);
FORCEPROP 2 LAST VOLTAGE 6.3V
J 2
(-1275 3425);
DISPLAY 0.553191 (-1275 3425);
DISPLAY INVISIBLE (-1275 3425);
FORCEPROP 1 LAST MATERIAL X6S
J 2
(-916 3454);
DISPLAY 0.574468 (-916 3454);
PAINT GREEN (-916 3454);
DISPLAY INVISIBLE (-916 3454);
FORCEPROP 2 LAST PACK_TYPE C0201
J 2
(-1100 3425);
DISPLAY 0.553191 (-1100 3425);
DISPLAY INVISIBLE (-1100 3425);
FORCEPROP 2 LAST TOLERANCE 20%
J 2
(-1000 3425);
DISPLAY 0.553191 (-1000 3425);
DISPLAY INVISIBLE (-1000 3425);
FORCEPROP 1 LAST PART_NUMBER SP_CH4221MEE01
J 2
(-1041 3463);
DISPLAY 0.574468 (-1041 3463);
PAINT GREEN (-1041 3463);
DISPLAY INVISIBLE (-1041 3463);
FORCEPROP 1 LAST PATH I272
J 2
(-925 3375);
DISPLAY 0.723404 (-925 3375);
DISPLAY INVISIBLE (-925 3375);
FORCEADD Q_CAP_DIFFBUS..2
R 2
(-925 3575);
FORCEPROP 1 LAST LOCATION C1548
J 2
(-675 3600);
DISPLAY 0.723404 (-675 3600);
PAINT GREEN (-675 3600);
FORCEPROP 2 LAST $SEC 1
J 2
(-750 3650);
DISPLAY 0.680851 (-750 3650);
PAINT MONO (-750 3650);
DISPLAY INVISIBLE (-750 3650);
FORCEPROP 2 LAST CDS_SEC 1
J 2
(-750 3650);
DISPLAY 0.680851 (-750 3650);
DISPLAY INVISIBLE (-750 3650);
FORCEPROP 2 LASTPIN (-850 3575) $PN 1
J 0
(-840 3585);
DISPLAY 0.808511 (-840 3585);
FORCEPROP 2 LASTPIN (-1000 3575) $PN 2
J 2
(-1010 3585);
DISPLAY 0.808511 (-1010 3585);
FORCEPROP 2 LAST PACK_TYPE C0201
J 2
(-925 3725);
DISPLAY 0.553191 (-925 3725);
PAINT GREEN (-925 3725);
FORCEPROP 2 LAST VALUE DIFF BUS_0.22UF
J 2
(-1075 3575);
DISPLAY 0.553191 (-1075 3575);
FORCEPROP 2 LAST VOLTAGE 6.3V
J 2
(-675 3725);
DISPLAY 0.553191 (-675 3725);
PAINT GREEN (-675 3725);
FORCEPROP 1 LAST MATERIAL X6S
J 2
(-966 3779);
DISPLAY 0.574468 (-966 3779);
PAINT GREEN (-966 3779);
FORCEPROP 2 LAST TOLERANCE 20%
J 2
(-825 3725);
DISPLAY 0.553191 (-825 3725);
PAINT GREEN (-825 3725);
FORCEPROP 2 LAST CDS_LIB pure_quanta
J 2
(-925 3575);
DISPLAY INVISIBLE (-925 3575);
FORCEPROP 1 LAST CDS_LMAN_SYM_OUTLINE -25,50,25,-50
J 2
(-925 3575);
DISPLAY 0.468085 (-925 3575);
PAINT GREEN (-925 3575);
DISPLAY INVISIBLE (-925 3575);
FORCEPROP 1 LAST PIN_NAMES_ROTATE TRUE
J 2
(-925 3575);
DISPLAY 0.489362 (-925 3575);
PAINT GREEN (-925 3575);
DISPLAY INVISIBLE (-925 3575);
FORCEPROP 1 LAST PART_NUMBER SP_CH4221MEE01
J 2
(-666 3663);
DISPLAY 0.574468 (-666 3663);
PAINT GREEN (-666 3663);
DISPLAY INVISIBLE (-666 3663);
FORCEPROP 1 LAST PATH I273
J 2
(-925 3575);
DISPLAY 0.723404 (-925 3575);
DISPLAY INVISIBLE (-925 3575);
FORCEADD Q_CAP_DIFFBUS..2
R 2
(-925 3525);
FORCEPROP 1 LAST LOCATION C1549
J 2
(-675 3550);
DISPLAY 0.723404 (-675 3550);
PAINT GREEN (-675 3550);
FORCEPROP 2 LAST $SEC 1
J 2
(-750 3600);
DISPLAY 0.680851 (-750 3600);
PAINT MONO (-750 3600);
DISPLAY INVISIBLE (-750 3600);
FORCEPROP 2 LAST CDS_SEC 1
J 2
(-750 3600);
DISPLAY 0.680851 (-750 3600);
DISPLAY INVISIBLE (-750 3600);
FORCEPROP 2 LASTPIN (-850 3525) $PN 1
J 0
(-840 3535);
DISPLAY 0.808511 (-840 3535);
FORCEPROP 2 LASTPIN (-1000 3525) $PN 2
J 2
(-1010 3535);
DISPLAY 0.808511 (-1010 3535);
FORCEPROP 2 LAST VALUE DIFF BUS_0.22UF
J 2
(-1075 3525);
DISPLAY 0.553191 (-1075 3525);
FORCEPROP 1 LAST CDS_LMAN_SYM_OUTLINE -25,50,25,-50
J 2
(-925 3525);
DISPLAY 0.468085 (-925 3525);
PAINT GREEN (-925 3525);
DISPLAY INVISIBLE (-925 3525);
FORCEPROP 2 LAST CDS_LIB pure_quanta
J 2
(-925 3525);
DISPLAY INVISIBLE (-925 3525);
FORCEPROP 1 LAST PIN_NAMES_ROTATE TRUE
J 2
(-925 3525);
DISPLAY 0.489362 (-925 3525);
PAINT GREEN (-925 3525);
DISPLAY INVISIBLE (-925 3525);
FORCEPROP 2 LAST VOLTAGE 6.3V
J 2
(-1275 3575);
DISPLAY 0.553191 (-1275 3575);
DISPLAY INVISIBLE (-1275 3575);
FORCEPROP 1 LAST MATERIAL X6S
J 2
(-916 3604);
DISPLAY 0.574468 (-916 3604);
PAINT GREEN (-916 3604);
DISPLAY INVISIBLE (-916 3604);
FORCEPROP 2 LAST PACK_TYPE C0201
J 2
(-1100 3575);
DISPLAY 0.553191 (-1100 3575);
DISPLAY INVISIBLE (-1100 3575);
FORCEPROP 2 LAST TOLERANCE 20%
J 2
(-1000 3575);
DISPLAY 0.553191 (-1000 3575);
DISPLAY INVISIBLE (-1000 3575);
FORCEPROP 1 LAST PART_NUMBER SP_CH4221MEE01
J 2
(-1041 3613);
DISPLAY 0.574468 (-1041 3613);
PAINT GREEN (-1041 3613);
DISPLAY INVISIBLE (-1041 3613);
FORCEPROP 1 LAST PATH I274
J 2
(-925 3525);
DISPLAY 0.723404 (-925 3525);
DISPLAY INVISIBLE (-925 3525);
FORCEADD TAP..1
(-375 200);
FORCEPROP 3 LASTPIN (-425 200) SIG_NAME P5E_CPU0_G3_TX_C_DN<0>
J 0
(-415 210);
DISPLAY 0.659574 (-415 210);
PAINT MONO (-415 210);
DISPLAY INVISIBLE (-415 210);
FORCEPROP 1 LASTPIN (-425 200) BN 0
J 0
(-437 208);
DISPLAY 0.680851 (-437 208);
PAINT GREEN (-437 208);
FORCEPROP 2 LAST CDS_LIB standard
J 0
(-375 200);
DISPLAY INVISIBLE (-375 200);
FORCEPROP 1 LAST BODY_TYPE PLUMBING
J 0
(-375 250);
DISPLAY 0.872340 (-375 250);
PAINT GREEN (-375 250);
DISPLAY INVISIBLE (-375 250);
FORCEPROP 1 LAST HDL_TAP TRUE
J 0
(-50 75);
DISPLAY 0.872340 (-50 75);
DISPLAY INVISIBLE (-50 75);
FORCEPROP 1 LAST PATH I275
J 0
(-377 200);
DISPLAY 0.872340 (-377 200);
PAINT GREEN (-377 200);
DISPLAY INVISIBLE (-377 200);
FORCEADD TAP..1
(-175 150);
FORCEPROP 3 LASTPIN (-225 150) SIG_NAME P5E_CPU0_G3_TX_C_DP<0>
J 0
(-215 160);
DISPLAY 0.659574 (-215 160);
PAINT MONO (-215 160);
DISPLAY INVISIBLE (-215 160);
FORCEPROP 1 LASTPIN (-225 150) BN 0
J 0
(-237 158);
DISPLAY 0.680851 (-237 158);
PAINT GREEN (-237 158);
FORCEPROP 2 LAST CDS_LIB standard
J 0
(-175 150);
DISPLAY INVISIBLE (-175 150);
FORCEPROP 1 LAST BODY_TYPE PLUMBING
J 0
(-175 200);
DISPLAY 0.872340 (-175 200);
PAINT GREEN (-175 200);
DISPLAY INVISIBLE (-175 200);
FORCEPROP 1 LAST HDL_TAP TRUE
J 0
(150 25);
DISPLAY 0.872340 (150 25);
DISPLAY INVISIBLE (150 25);
FORCEPROP 1 LAST PATH I276
J 0
(-177 150);
DISPLAY 0.872340 (-177 150);
PAINT GREEN (-177 150);
DISPLAY INVISIBLE (-177 150);
FORCEADD TAP..1
(-175 350);
FORCEPROP 3 LASTPIN (-225 350) SIG_NAME P5E_CPU0_G3_TX_C_DP<1>
J 0
(-215 360);
DISPLAY 0.659574 (-215 360);
PAINT MONO (-215 360);
DISPLAY INVISIBLE (-215 360);
FORCEPROP 1 LASTPIN (-225 350) BN 1
J 0
(-237 358);
DISPLAY 0.680851 (-237 358);
PAINT GREEN (-237 358);
FORCEPROP 2 LAST CDS_LIB standard
J 0
(-175 350);
DISPLAY INVISIBLE (-175 350);
FORCEPROP 1 LAST BODY_TYPE PLUMBING
J 0
(-175 400);
DISPLAY 0.872340 (-175 400);
PAINT GREEN (-175 400);
DISPLAY INVISIBLE (-175 400);
FORCEPROP 1 LAST HDL_TAP TRUE
J 0
(150 225);
DISPLAY 0.872340 (150 225);
DISPLAY INVISIBLE (150 225);
FORCEPROP 1 LAST PATH I277
J 0
(-177 350);
DISPLAY 0.872340 (-177 350);
PAINT GREEN (-177 350);
DISPLAY INVISIBLE (-177 350);
FORCEADD TAP..1
(-375 400);
FORCEPROP 3 LASTPIN (-425 400) SIG_NAME P5E_CPU0_G3_TX_C_DN<1>
J 0
(-415 410);
DISPLAY 0.659574 (-415 410);
PAINT MONO (-415 410);
DISPLAY INVISIBLE (-415 410);
FORCEPROP 1 LASTPIN (-425 400) BN 1
J 0
(-437 408);
DISPLAY 0.680851 (-437 408);
PAINT GREEN (-437 408);
FORCEPROP 2 LAST CDS_LIB standard
J 0
(-375 400);
DISPLAY INVISIBLE (-375 400);
FORCEPROP 1 LAST BODY_TYPE PLUMBING
J 0
(-375 450);
DISPLAY 0.872340 (-375 450);
PAINT GREEN (-375 450);
DISPLAY INVISIBLE (-375 450);
FORCEPROP 1 LAST HDL_TAP TRUE
J 0
(-50 275);
DISPLAY 0.872340 (-50 275);
DISPLAY INVISIBLE (-50 275);
FORCEPROP 1 LAST PATH I278
J 0
(-377 400);
DISPLAY 0.872340 (-377 400);
PAINT GREEN (-377 400);
DISPLAY INVISIBLE (-377 400);
FORCEADD TAP..1
(-375 600);
FORCEPROP 3 LASTPIN (-425 600) SIG_NAME P5E_CPU0_G3_TX_C_DN<2>
J 0
(-415 610);
DISPLAY 0.659574 (-415 610);
PAINT MONO (-415 610);
DISPLAY INVISIBLE (-415 610);
FORCEPROP 1 LASTPIN (-425 600) BN 2
J 0
(-437 608);
DISPLAY 0.680851 (-437 608);
PAINT GREEN (-437 608);
FORCEPROP 2 LAST CDS_LIB standard
J 0
(-375 600);
DISPLAY INVISIBLE (-375 600);
FORCEPROP 1 LAST BODY_TYPE PLUMBING
J 0
(-375 650);
DISPLAY 0.872340 (-375 650);
PAINT GREEN (-375 650);
DISPLAY INVISIBLE (-375 650);
FORCEPROP 1 LAST HDL_TAP TRUE
J 0
(-50 475);
DISPLAY 0.872340 (-50 475);
DISPLAY INVISIBLE (-50 475);
FORCEPROP 1 LAST PATH I279
J 0
(-377 600);
DISPLAY 0.872340 (-377 600);
PAINT GREEN (-377 600);
DISPLAY INVISIBLE (-377 600);
FORCEADD TAP..1
(-175 550);
FORCEPROP 3 LASTPIN (-225 550) SIG_NAME P5E_CPU0_G3_TX_C_DP<2>
J 0
(-215 560);
DISPLAY 0.659574 (-215 560);
PAINT MONO (-215 560);
DISPLAY INVISIBLE (-215 560);
FORCEPROP 1 LASTPIN (-225 550) BN 2
J 0
(-237 558);
DISPLAY 0.680851 (-237 558);
PAINT GREEN (-237 558);
FORCEPROP 2 LAST CDS_LIB standard
J 0
(-175 550);
DISPLAY INVISIBLE (-175 550);
FORCEPROP 1 LAST BODY_TYPE PLUMBING
J 0
(-175 600);
DISPLAY 0.872340 (-175 600);
PAINT GREEN (-175 600);
DISPLAY INVISIBLE (-175 600);
FORCEPROP 1 LAST HDL_TAP TRUE
J 0
(150 425);
DISPLAY 0.872340 (150 425);
DISPLAY INVISIBLE (150 425);
FORCEPROP 1 LAST PATH I280
J 0
(-177 550);
DISPLAY 0.872340 (-177 550);
PAINT GREEN (-177 550);
DISPLAY INVISIBLE (-177 550);
FORCEADD TAP..1
(-175 750);
FORCEPROP 3 LASTPIN (-225 750) SIG_NAME P5E_CPU0_G3_TX_C_DP<3>
J 0
(-215 760);
DISPLAY 0.659574 (-215 760);
PAINT MONO (-215 760);
DISPLAY INVISIBLE (-215 760);
FORCEPROP 1 LASTPIN (-225 750) BN 3
J 0
(-237 758);
DISPLAY 0.680851 (-237 758);
PAINT GREEN (-237 758);
FORCEPROP 2 LAST CDS_LIB standard
J 0
(-175 750);
DISPLAY INVISIBLE (-175 750);
FORCEPROP 1 LAST BODY_TYPE PLUMBING
J 0
(-175 800);
DISPLAY 0.872340 (-175 800);
PAINT GREEN (-175 800);
DISPLAY INVISIBLE (-175 800);
FORCEPROP 1 LAST HDL_TAP TRUE
J 0
(150 625);
DISPLAY 0.872340 (150 625);
DISPLAY INVISIBLE (150 625);
FORCEPROP 1 LAST PATH I281
J 0
(-177 750);
DISPLAY 0.872340 (-177 750);
PAINT GREEN (-177 750);
DISPLAY INVISIBLE (-177 750);
FORCEADD TAP..1
(-375 1000);
FORCEPROP 3 LASTPIN (-425 1000) SIG_NAME P5E_CPU0_G3_TX_C_DN<4>
J 0
(-415 1010);
DISPLAY 0.659574 (-415 1010);
PAINT MONO (-415 1010);
DISPLAY INVISIBLE (-415 1010);
FORCEPROP 1 LASTPIN (-425 1000) BN 4
J 0
(-437 1008);
DISPLAY 0.680851 (-437 1008);
PAINT GREEN (-437 1008);
FORCEPROP 2 LAST CDS_LIB standard
J 0
(-375 1000);
DISPLAY INVISIBLE (-375 1000);
FORCEPROP 1 LAST BODY_TYPE PLUMBING
J 0
(-375 1050);
DISPLAY 0.872340 (-375 1050);
PAINT GREEN (-375 1050);
DISPLAY INVISIBLE (-375 1050);
FORCEPROP 1 LAST HDL_TAP TRUE
J 0
(-50 875);
DISPLAY 0.872340 (-50 875);
DISPLAY INVISIBLE (-50 875);
FORCEPROP 1 LAST PATH I282
J 0
(-377 1000);
DISPLAY 0.872340 (-377 1000);
PAINT GREEN (-377 1000);
DISPLAY INVISIBLE (-377 1000);
FORCEADD TAP..1
(-375 800);
FORCEPROP 3 LASTPIN (-425 800) SIG_NAME P5E_CPU0_G3_TX_C_DN<3>
J 0
(-415 810);
DISPLAY 0.659574 (-415 810);
PAINT MONO (-415 810);
DISPLAY INVISIBLE (-415 810);
FORCEPROP 1 LASTPIN (-425 800) BN 3
J 0
(-437 808);
DISPLAY 0.680851 (-437 808);
PAINT GREEN (-437 808);
FORCEPROP 2 LAST CDS_LIB standard
J 0
(-375 800);
DISPLAY INVISIBLE (-375 800);
FORCEPROP 1 LAST BODY_TYPE PLUMBING
J 0
(-375 850);
DISPLAY 0.872340 (-375 850);
PAINT GREEN (-375 850);
DISPLAY INVISIBLE (-375 850);
FORCEPROP 1 LAST HDL_TAP TRUE
J 0
(-50 675);
DISPLAY 0.872340 (-50 675);
DISPLAY INVISIBLE (-50 675);
FORCEPROP 1 LAST PATH I283
J 0
(-377 800);
DISPLAY 0.872340 (-377 800);
PAINT GREEN (-377 800);
DISPLAY INVISIBLE (-377 800);
FORCEADD TAP..1
(-175 950);
FORCEPROP 3 LASTPIN (-225 950) SIG_NAME P5E_CPU0_G3_TX_C_DP<4>
J 0
(-215 960);
DISPLAY 0.659574 (-215 960);
PAINT MONO (-215 960);
DISPLAY INVISIBLE (-215 960);
FORCEPROP 1 LASTPIN (-225 950) BN 4
J 0
(-237 958);
DISPLAY 0.680851 (-237 958);
PAINT GREEN (-237 958);
FORCEPROP 2 LAST CDS_LIB standard
J 0
(-175 950);
DISPLAY INVISIBLE (-175 950);
FORCEPROP 1 LAST BODY_TYPE PLUMBING
J 0
(-175 1000);
DISPLAY 0.872340 (-175 1000);
PAINT GREEN (-175 1000);
DISPLAY INVISIBLE (-175 1000);
FORCEPROP 1 LAST HDL_TAP TRUE
J 0
(150 825);
DISPLAY 0.872340 (150 825);
DISPLAY INVISIBLE (150 825);
FORCEPROP 1 LAST PATH I284
J 0
(-177 950);
DISPLAY 0.872340 (-177 950);
PAINT GREEN (-177 950);
DISPLAY INVISIBLE (-177 950);
FORCEADD TAP..1
(-375 1200);
FORCEPROP 3 LASTPIN (-425 1200) SIG_NAME P5E_CPU0_G3_TX_C_DN<5>
J 0
(-415 1210);
DISPLAY 0.659574 (-415 1210);
PAINT MONO (-415 1210);
DISPLAY INVISIBLE (-415 1210);
FORCEPROP 1 LASTPIN (-425 1200) BN 5
J 0
(-437 1208);
DISPLAY 0.680851 (-437 1208);
PAINT GREEN (-437 1208);
FORCEPROP 2 LAST CDS_LIB standard
J 0
(-375 1200);
DISPLAY INVISIBLE (-375 1200);
FORCEPROP 1 LAST BODY_TYPE PLUMBING
J 0
(-375 1250);
DISPLAY 0.872340 (-375 1250);
PAINT GREEN (-375 1250);
DISPLAY INVISIBLE (-375 1250);
FORCEPROP 1 LAST HDL_TAP TRUE
J 0
(-50 1075);
DISPLAY 0.872340 (-50 1075);
DISPLAY INVISIBLE (-50 1075);
FORCEPROP 1 LAST PATH I285
J 0
(-377 1200);
DISPLAY 0.872340 (-377 1200);
PAINT GREEN (-377 1200);
DISPLAY INVISIBLE (-377 1200);
FORCEADD TAP..1
(-175 1150);
FORCEPROP 3 LASTPIN (-225 1150) SIG_NAME P5E_CPU0_G3_TX_C_DP<5>
J 0
(-215 1160);
DISPLAY 0.659574 (-215 1160);
PAINT MONO (-215 1160);
DISPLAY INVISIBLE (-215 1160);
FORCEPROP 1 LASTPIN (-225 1150) BN 5
J 0
(-237 1158);
DISPLAY 0.680851 (-237 1158);
PAINT GREEN (-237 1158);
FORCEPROP 2 LAST CDS_LIB standard
J 0
(-175 1150);
DISPLAY INVISIBLE (-175 1150);
FORCEPROP 1 LAST BODY_TYPE PLUMBING
J 0
(-175 1200);
DISPLAY 0.872340 (-175 1200);
PAINT GREEN (-175 1200);
DISPLAY INVISIBLE (-175 1200);
FORCEPROP 1 LAST HDL_TAP TRUE
J 0
(150 1025);
DISPLAY 0.872340 (150 1025);
DISPLAY INVISIBLE (150 1025);
FORCEPROP 1 LAST PATH I286
J 0
(-177 1150);
DISPLAY 0.872340 (-177 1150);
PAINT GREEN (-177 1150);
DISPLAY INVISIBLE (-177 1150);
FORCEADD TAP..1
(-375 1400);
FORCEPROP 3 LASTPIN (-425 1400) SIG_NAME P5E_CPU0_G3_TX_C_DN<6>
J 0
(-415 1410);
DISPLAY 0.659574 (-415 1410);
PAINT MONO (-415 1410);
DISPLAY INVISIBLE (-415 1410);
FORCEPROP 1 LASTPIN (-425 1400) BN 6
J 0
(-437 1408);
DISPLAY 0.680851 (-437 1408);
PAINT GREEN (-437 1408);
FORCEPROP 2 LAST CDS_LIB standard
J 0
(-375 1400);
DISPLAY INVISIBLE (-375 1400);
FORCEPROP 1 LAST BODY_TYPE PLUMBING
J 0
(-375 1450);
DISPLAY 0.872340 (-375 1450);
PAINT GREEN (-375 1450);
DISPLAY INVISIBLE (-375 1450);
FORCEPROP 1 LAST HDL_TAP TRUE
J 0
(-50 1275);
DISPLAY 0.872340 (-50 1275);
DISPLAY INVISIBLE (-50 1275);
FORCEPROP 1 LAST PATH I287
J 0
(-377 1400);
DISPLAY 0.872340 (-377 1400);
PAINT GREEN (-377 1400);
DISPLAY INVISIBLE (-377 1400);
FORCEADD TAP..1
(-175 1350);
FORCEPROP 3 LASTPIN (-225 1350) SIG_NAME P5E_CPU0_G3_TX_C_DP<6>
J 0
(-215 1360);
DISPLAY 0.659574 (-215 1360);
PAINT MONO (-215 1360);
DISPLAY INVISIBLE (-215 1360);
FORCEPROP 1 LASTPIN (-225 1350) BN 6
J 0
(-237 1358);
DISPLAY 0.680851 (-237 1358);
PAINT GREEN (-237 1358);
FORCEPROP 2 LAST CDS_LIB standard
J 0
(-175 1350);
DISPLAY INVISIBLE (-175 1350);
FORCEPROP 1 LAST BODY_TYPE PLUMBING
J 0
(-175 1400);
DISPLAY 0.872340 (-175 1400);
PAINT GREEN (-175 1400);
DISPLAY INVISIBLE (-175 1400);
FORCEPROP 1 LAST HDL_TAP TRUE
J 0
(150 1225);
DISPLAY 0.872340 (150 1225);
DISPLAY INVISIBLE (150 1225);
FORCEPROP 1 LAST PATH I288
J 0
(-177 1350);
DISPLAY 0.872340 (-177 1350);
PAINT GREEN (-177 1350);
DISPLAY INVISIBLE (-177 1350);
FORCEADD TAP..1
(-375 1600);
FORCEPROP 3 LASTPIN (-425 1600) SIG_NAME P5E_CPU0_G3_TX_C_DN<7>
J 0
(-415 1610);
DISPLAY 0.659574 (-415 1610);
PAINT MONO (-415 1610);
DISPLAY INVISIBLE (-415 1610);
FORCEPROP 1 LASTPIN (-425 1600) BN 7
J 0
(-437 1608);
DISPLAY 0.680851 (-437 1608);
PAINT GREEN (-437 1608);
FORCEPROP 2 LAST CDS_LIB standard
J 0
(-375 1600);
DISPLAY INVISIBLE (-375 1600);
FORCEPROP 1 LAST BODY_TYPE PLUMBING
J 0
(-375 1650);
DISPLAY 0.872340 (-375 1650);
PAINT GREEN (-375 1650);
DISPLAY INVISIBLE (-375 1650);
FORCEPROP 1 LAST HDL_TAP TRUE
J 0
(-50 1475);
DISPLAY 0.872340 (-50 1475);
DISPLAY INVISIBLE (-50 1475);
FORCEPROP 1 LAST PATH I289
J 0
(-377 1600);
DISPLAY 0.872340 (-377 1600);
PAINT GREEN (-377 1600);
DISPLAY INVISIBLE (-377 1600);
FORCEADD TAP..1
(-175 1550);
FORCEPROP 3 LASTPIN (-225 1550) SIG_NAME P5E_CPU0_G3_TX_C_DP<7>
J 0
(-215 1560);
DISPLAY 0.659574 (-215 1560);
PAINT MONO (-215 1560);
DISPLAY INVISIBLE (-215 1560);
FORCEPROP 1 LASTPIN (-225 1550) BN 7
J 0
(-237 1558);
DISPLAY 0.680851 (-237 1558);
PAINT GREEN (-237 1558);
FORCEPROP 2 LAST CDS_LIB standard
J 0
(-175 1550);
DISPLAY INVISIBLE (-175 1550);
FORCEPROP 1 LAST BODY_TYPE PLUMBING
J 0
(-175 1600);
DISPLAY 0.872340 (-175 1600);
PAINT GREEN (-175 1600);
DISPLAY INVISIBLE (-175 1600);
FORCEPROP 1 LAST HDL_TAP TRUE
J 0
(150 1425);
DISPLAY 0.872340 (150 1425);
DISPLAY INVISIBLE (150 1425);
FORCEPROP 1 LAST PATH I290
J 0
(-177 1550);
DISPLAY 0.872340 (-177 1550);
PAINT GREEN (-177 1550);
DISPLAY INVISIBLE (-177 1550);
FORCEADD OFFPAGE..2
(825 1575);
FORCEPROP 2 LAST $XR0 131 
J 0
(1014 1575);
DISPLAY 0.638298 (1014 1575);
PAINT MONO (1014 1575);
FORCEPROP 2 LAST CDS_LIB standard
J 0
(825 1575);
DISPLAY INVISIBLE (825 1575);
FORCEPROP 1 LAST OFFPAGE TRUE
J 0
(1150 1450);
DISPLAY 0.872340 (1150 1450);
DISPLAY INVISIBLE (1150 1450);
FORCEPROP 1 LAST COMMENT_BODY TRUE
J 0
(780 1480);
DISPLAY 0.872340 (780 1480);
PAINT GREEN (780 1480);
DISPLAY INVISIBLE (780 1480);
FORCEPROP 2 LAST PATH I291
J 0
(1025 1625);
DISPLAY 1.021277 (1025 1625);
DISPLAY INVISIBLE (1025 1625);
FORCEADD OFFPAGE..2
(825 1625);
FORCEPROP 2 LAST $XR0 131 
J 0
(1014 1625);
DISPLAY 0.638298 (1014 1625);
PAINT MONO (1014 1625);
FORCEPROP 2 LAST CDS_LIB standard
J 0
(825 1625);
DISPLAY INVISIBLE (825 1625);
FORCEPROP 1 LAST OFFPAGE TRUE
J 0
(1150 1500);
DISPLAY 0.872340 (1150 1500);
DISPLAY INVISIBLE (1150 1500);
FORCEPROP 1 LAST COMMENT_BODY TRUE
J 0
(780 1530);
DISPLAY 0.872340 (780 1530);
PAINT GREEN (780 1530);
DISPLAY INVISIBLE (780 1530);
FORCEPROP 2 LAST PATH I292
J 0
(1025 1675);
DISPLAY 1.021277 (1025 1675);
DISPLAY INVISIBLE (1025 1675);
FORCEADD TAP..1
(-375 2175);
FORCEPROP 3 LASTPIN (-425 2175) SIG_NAME P5E_CPU0_G3_TX_C_DN<8>
J 0
(-415 2185);
DISPLAY 0.659574 (-415 2185);
PAINT MONO (-415 2185);
DISPLAY INVISIBLE (-415 2185);
FORCEPROP 1 LASTPIN (-425 2175) BN 8
J 0
(-437 2183);
DISPLAY 0.680851 (-437 2183);
PAINT GREEN (-437 2183);
FORCEPROP 2 LAST CDS_LIB standard
J 0
(-375 2175);
DISPLAY INVISIBLE (-375 2175);
FORCEPROP 1 LAST BODY_TYPE PLUMBING
J 0
(-375 2225);
DISPLAY 0.872340 (-375 2225);
PAINT GREEN (-375 2225);
DISPLAY INVISIBLE (-375 2225);
FORCEPROP 1 LAST HDL_TAP TRUE
J 0
(-50 2050);
DISPLAY 0.872340 (-50 2050);
DISPLAY INVISIBLE (-50 2050);
FORCEPROP 1 LAST PATH I293
J 0
(-377 2175);
DISPLAY 0.872340 (-377 2175);
PAINT GREEN (-377 2175);
DISPLAY INVISIBLE (-377 2175);
FORCEADD TAP..1
(-175 2125);
FORCEPROP 3 LASTPIN (-225 2125) SIG_NAME P5E_CPU0_G3_TX_C_DP<8>
J 0
(-215 2135);
DISPLAY 0.659574 (-215 2135);
PAINT MONO (-215 2135);
DISPLAY INVISIBLE (-215 2135);
FORCEPROP 1 LASTPIN (-225 2125) BN 8
J 0
(-237 2133);
DISPLAY 0.680851 (-237 2133);
PAINT GREEN (-237 2133);
FORCEPROP 2 LAST CDS_LIB standard
J 0
(-175 2125);
DISPLAY INVISIBLE (-175 2125);
FORCEPROP 1 LAST BODY_TYPE PLUMBING
J 0
(-175 2175);
DISPLAY 0.872340 (-175 2175);
PAINT GREEN (-175 2175);
DISPLAY INVISIBLE (-175 2175);
FORCEPROP 1 LAST HDL_TAP TRUE
J 0
(150 2000);
DISPLAY 0.872340 (150 2000);
DISPLAY INVISIBLE (150 2000);
FORCEPROP 1 LAST PATH I294
J 0
(-177 2125);
DISPLAY 0.872340 (-177 2125);
PAINT GREEN (-177 2125);
DISPLAY INVISIBLE (-177 2125);
FORCEADD TAP..1
(-375 2375);
FORCEPROP 3 LASTPIN (-425 2375) SIG_NAME P5E_CPU0_G3_TX_C_DN<9>
J 0
(-415 2385);
DISPLAY 0.659574 (-415 2385);
PAINT MONO (-415 2385);
DISPLAY INVISIBLE (-415 2385);
FORCEPROP 1 LASTPIN (-425 2375) BN 9
J 0
(-437 2383);
DISPLAY 0.680851 (-437 2383);
PAINT GREEN (-437 2383);
FORCEPROP 2 LAST CDS_LIB standard
J 0
(-375 2375);
DISPLAY INVISIBLE (-375 2375);
FORCEPROP 1 LAST BODY_TYPE PLUMBING
J 0
(-375 2425);
DISPLAY 0.872340 (-375 2425);
PAINT GREEN (-375 2425);
DISPLAY INVISIBLE (-375 2425);
FORCEPROP 1 LAST HDL_TAP TRUE
J 0
(-50 2250);
DISPLAY 0.872340 (-50 2250);
DISPLAY INVISIBLE (-50 2250);
FORCEPROP 1 LAST PATH I295
J 0
(-377 2375);
DISPLAY 0.872340 (-377 2375);
PAINT GREEN (-377 2375);
DISPLAY INVISIBLE (-377 2375);
FORCEADD TAP..1
(-175 2325);
FORCEPROP 3 LASTPIN (-225 2325) SIG_NAME P5E_CPU0_G3_TX_C_DP<9>
J 0
(-215 2335);
DISPLAY 0.659574 (-215 2335);
PAINT MONO (-215 2335);
DISPLAY INVISIBLE (-215 2335);
FORCEPROP 1 LASTPIN (-225 2325) BN 9
J 0
(-237 2333);
DISPLAY 0.680851 (-237 2333);
PAINT GREEN (-237 2333);
FORCEPROP 2 LAST CDS_LIB standard
J 0
(-175 2325);
DISPLAY INVISIBLE (-175 2325);
FORCEPROP 1 LAST BODY_TYPE PLUMBING
J 0
(-175 2375);
DISPLAY 0.872340 (-175 2375);
PAINT GREEN (-175 2375);
DISPLAY INVISIBLE (-175 2375);
FORCEPROP 1 LAST HDL_TAP TRUE
J 0
(150 2200);
DISPLAY 0.872340 (150 2200);
DISPLAY INVISIBLE (150 2200);
FORCEPROP 1 LAST PATH I296
J 0
(-177 2325);
DISPLAY 0.872340 (-177 2325);
PAINT GREEN (-177 2325);
DISPLAY INVISIBLE (-177 2325);
FORCEADD TAP..1
(-175 2525);
FORCEPROP 3 LASTPIN (-225 2525) SIG_NAME P5E_CPU0_G3_TX_C_DP<10>
J 0
(-215 2535);
DISPLAY 0.659574 (-215 2535);
PAINT MONO (-215 2535);
DISPLAY INVISIBLE (-215 2535);
FORCEPROP 1 LASTPIN (-225 2525) BN 10
J 0
(-237 2533);
DISPLAY 0.680851 (-237 2533);
PAINT GREEN (-237 2533);
FORCEPROP 2 LAST CDS_LIB standard
J 0
(-175 2525);
DISPLAY INVISIBLE (-175 2525);
FORCEPROP 1 LAST BODY_TYPE PLUMBING
J 0
(-175 2575);
DISPLAY 0.872340 (-175 2575);
PAINT GREEN (-175 2575);
DISPLAY INVISIBLE (-175 2575);
FORCEPROP 1 LAST HDL_TAP TRUE
J 0
(150 2400);
DISPLAY 0.872340 (150 2400);
DISPLAY INVISIBLE (150 2400);
FORCEPROP 1 LAST PATH I297
J 0
(-177 2525);
DISPLAY 0.872340 (-177 2525);
PAINT GREEN (-177 2525);
DISPLAY INVISIBLE (-177 2525);
FORCEADD TAP..1
(-375 2775);
FORCEPROP 3 LASTPIN (-425 2775) SIG_NAME P5E_CPU0_G3_TX_C_DN<11>
J 0
(-415 2785);
DISPLAY 0.659574 (-415 2785);
PAINT MONO (-415 2785);
DISPLAY INVISIBLE (-415 2785);
FORCEPROP 1 LASTPIN (-425 2775) BN 11
J 0
(-437 2783);
DISPLAY 0.680851 (-437 2783);
PAINT GREEN (-437 2783);
FORCEPROP 2 LAST CDS_LIB standard
J 0
(-375 2775);
DISPLAY INVISIBLE (-375 2775);
FORCEPROP 1 LAST BODY_TYPE PLUMBING
J 0
(-375 2825);
DISPLAY 0.872340 (-375 2825);
PAINT GREEN (-375 2825);
DISPLAY INVISIBLE (-375 2825);
FORCEPROP 1 LAST HDL_TAP TRUE
J 0
(-50 2650);
DISPLAY 0.872340 (-50 2650);
DISPLAY INVISIBLE (-50 2650);
FORCEPROP 1 LAST PATH I298
J 0
(-377 2775);
DISPLAY 0.872340 (-377 2775);
PAINT GREEN (-377 2775);
DISPLAY INVISIBLE (-377 2775);
FORCEADD TAP..1
(-375 2575);
FORCEPROP 3 LASTPIN (-425 2575) SIG_NAME P5E_CPU0_G3_TX_C_DN<10>
J 0
(-415 2585);
DISPLAY 0.659574 (-415 2585);
PAINT MONO (-415 2585);
DISPLAY INVISIBLE (-415 2585);
FORCEPROP 1 LASTPIN (-425 2575) BN 10
J 0
(-437 2583);
DISPLAY 0.680851 (-437 2583);
PAINT GREEN (-437 2583);
FORCEPROP 2 LAST CDS_LIB standard
J 0
(-375 2575);
DISPLAY INVISIBLE (-375 2575);
FORCEPROP 1 LAST BODY_TYPE PLUMBING
J 0
(-375 2625);
DISPLAY 0.872340 (-375 2625);
PAINT GREEN (-375 2625);
DISPLAY INVISIBLE (-375 2625);
FORCEPROP 1 LAST HDL_TAP TRUE
J 0
(-50 2450);
DISPLAY 0.872340 (-50 2450);
DISPLAY INVISIBLE (-50 2450);
FORCEPROP 1 LAST PATH I299
J 0
(-377 2575);
DISPLAY 0.872340 (-377 2575);
PAINT GREEN (-377 2575);
DISPLAY INVISIBLE (-377 2575);
FORCEADD TAP..1
(-175 2725);
FORCEPROP 3 LASTPIN (-225 2725) SIG_NAME P5E_CPU0_G3_TX_C_DP<11>
J 0
(-215 2735);
DISPLAY 0.659574 (-215 2735);
PAINT MONO (-215 2735);
DISPLAY INVISIBLE (-215 2735);
FORCEPROP 1 LASTPIN (-225 2725) BN 11
J 0
(-237 2733);
DISPLAY 0.680851 (-237 2733);
PAINT GREEN (-237 2733);
FORCEPROP 2 LAST CDS_LIB standard
J 0
(-175 2725);
DISPLAY INVISIBLE (-175 2725);
FORCEPROP 1 LAST BODY_TYPE PLUMBING
J 0
(-175 2775);
DISPLAY 0.872340 (-175 2775);
PAINT GREEN (-175 2775);
DISPLAY INVISIBLE (-175 2775);
FORCEPROP 1 LAST HDL_TAP TRUE
J 0
(150 2600);
DISPLAY 0.872340 (150 2600);
DISPLAY INVISIBLE (150 2600);
FORCEPROP 1 LAST PATH I300
J 0
(-177 2725);
DISPLAY 0.872340 (-177 2725);
PAINT GREEN (-177 2725);
DISPLAY INVISIBLE (-177 2725);
FORCEADD TAP..1
(-375 2975);
FORCEPROP 3 LASTPIN (-425 2975) SIG_NAME P5E_CPU0_G3_TX_C_DN<12>
J 0
(-415 2985);
DISPLAY 0.659574 (-415 2985);
PAINT MONO (-415 2985);
DISPLAY INVISIBLE (-415 2985);
FORCEPROP 1 LASTPIN (-425 2975) BN 12
J 0
(-437 2983);
DISPLAY 0.680851 (-437 2983);
PAINT GREEN (-437 2983);
FORCEPROP 2 LAST CDS_LIB standard
J 0
(-375 2975);
DISPLAY INVISIBLE (-375 2975);
FORCEPROP 1 LAST BODY_TYPE PLUMBING
J 0
(-375 3025);
DISPLAY 0.872340 (-375 3025);
PAINT GREEN (-375 3025);
DISPLAY INVISIBLE (-375 3025);
FORCEPROP 1 LAST HDL_TAP TRUE
J 0
(-50 2850);
DISPLAY 0.872340 (-50 2850);
DISPLAY INVISIBLE (-50 2850);
FORCEPROP 1 LAST PATH I301
J 0
(-377 2975);
DISPLAY 0.872340 (-377 2975);
PAINT GREEN (-377 2975);
DISPLAY INVISIBLE (-377 2975);
FORCEADD TAP..1
(-175 2925);
FORCEPROP 3 LASTPIN (-225 2925) SIG_NAME P5E_CPU0_G3_TX_C_DP<12>
J 0
(-215 2935);
DISPLAY 0.659574 (-215 2935);
PAINT MONO (-215 2935);
DISPLAY INVISIBLE (-215 2935);
FORCEPROP 1 LASTPIN (-225 2925) BN 12
J 0
(-237 2933);
DISPLAY 0.680851 (-237 2933);
PAINT GREEN (-237 2933);
FORCEPROP 2 LAST CDS_LIB standard
J 0
(-175 2925);
DISPLAY INVISIBLE (-175 2925);
FORCEPROP 1 LAST BODY_TYPE PLUMBING
J 0
(-175 2975);
DISPLAY 0.872340 (-175 2975);
PAINT GREEN (-175 2975);
DISPLAY INVISIBLE (-175 2975);
FORCEPROP 1 LAST HDL_TAP TRUE
J 0
(150 2800);
DISPLAY 0.872340 (150 2800);
DISPLAY INVISIBLE (150 2800);
FORCEPROP 1 LAST PATH I302
J 0
(-177 2925);
DISPLAY 0.872340 (-177 2925);
PAINT GREEN (-177 2925);
DISPLAY INVISIBLE (-177 2925);
FORCEADD TAP..1
(-375 3175);
FORCEPROP 3 LASTPIN (-425 3175) SIG_NAME P5E_CPU0_G3_TX_C_DN<13>
J 0
(-415 3185);
DISPLAY 0.659574 (-415 3185);
PAINT MONO (-415 3185);
DISPLAY INVISIBLE (-415 3185);
FORCEPROP 1 LASTPIN (-425 3175) BN 13
J 0
(-437 3183);
DISPLAY 0.680851 (-437 3183);
PAINT GREEN (-437 3183);
FORCEPROP 2 LAST CDS_LIB standard
J 0
(-375 3175);
DISPLAY INVISIBLE (-375 3175);
FORCEPROP 1 LAST BODY_TYPE PLUMBING
J 0
(-375 3225);
DISPLAY 0.872340 (-375 3225);
PAINT GREEN (-375 3225);
DISPLAY INVISIBLE (-375 3225);
FORCEPROP 1 LAST HDL_TAP TRUE
J 0
(-50 3050);
DISPLAY 0.872340 (-50 3050);
DISPLAY INVISIBLE (-50 3050);
FORCEPROP 1 LAST PATH I303
J 0
(-377 3175);
DISPLAY 0.872340 (-377 3175);
PAINT GREEN (-377 3175);
DISPLAY INVISIBLE (-377 3175);
FORCEADD TAP..1
(-175 3325);
FORCEPROP 3 LASTPIN (-225 3325) SIG_NAME P5E_CPU0_G3_TX_C_DP<14>
J 0
(-215 3335);
DISPLAY 0.659574 (-215 3335);
PAINT MONO (-215 3335);
DISPLAY INVISIBLE (-215 3335);
FORCEPROP 1 LASTPIN (-225 3325) BN 14
J 0
(-237 3333);
DISPLAY 0.680851 (-237 3333);
PAINT GREEN (-237 3333);
FORCEPROP 2 LAST CDS_LIB standard
J 0
(-175 3325);
DISPLAY INVISIBLE (-175 3325);
FORCEPROP 1 LAST BODY_TYPE PLUMBING
J 0
(-175 3375);
DISPLAY 0.872340 (-175 3375);
PAINT GREEN (-175 3375);
DISPLAY INVISIBLE (-175 3375);
FORCEPROP 1 LAST HDL_TAP TRUE
J 0
(150 3200);
DISPLAY 0.872340 (150 3200);
DISPLAY INVISIBLE (150 3200);
FORCEPROP 1 LAST PATH I304
J 0
(-177 3325);
DISPLAY 0.872340 (-177 3325);
PAINT GREEN (-177 3325);
DISPLAY INVISIBLE (-177 3325);
FORCEADD TAP..1
(-175 3125);
FORCEPROP 3 LASTPIN (-225 3125) SIG_NAME P5E_CPU0_G3_TX_C_DP<13>
J 0
(-215 3135);
DISPLAY 0.659574 (-215 3135);
PAINT MONO (-215 3135);
DISPLAY INVISIBLE (-215 3135);
FORCEPROP 1 LASTPIN (-225 3125) BN 13
J 0
(-237 3133);
DISPLAY 0.680851 (-237 3133);
PAINT GREEN (-237 3133);
FORCEPROP 2 LAST CDS_LIB standard
J 0
(-175 3125);
DISPLAY INVISIBLE (-175 3125);
FORCEPROP 1 LAST BODY_TYPE PLUMBING
J 0
(-175 3175);
DISPLAY 0.872340 (-175 3175);
PAINT GREEN (-175 3175);
DISPLAY INVISIBLE (-175 3175);
FORCEPROP 1 LAST HDL_TAP TRUE
J 0
(150 3000);
DISPLAY 0.872340 (150 3000);
DISPLAY INVISIBLE (150 3000);
FORCEPROP 1 LAST PATH I305
J 0
(-177 3125);
DISPLAY 0.872340 (-177 3125);
PAINT GREEN (-177 3125);
DISPLAY INVISIBLE (-177 3125);
FORCEADD TAP..1
(-375 3375);
FORCEPROP 3 LASTPIN (-425 3375) SIG_NAME P5E_CPU0_G3_TX_C_DN<14>
J 0
(-415 3385);
DISPLAY 0.659574 (-415 3385);
PAINT MONO (-415 3385);
DISPLAY INVISIBLE (-415 3385);
FORCEPROP 1 LASTPIN (-425 3375) BN 14
J 0
(-437 3383);
DISPLAY 0.680851 (-437 3383);
PAINT GREEN (-437 3383);
FORCEPROP 2 LAST CDS_LIB standard
J 0
(-375 3375);
DISPLAY INVISIBLE (-375 3375);
FORCEPROP 1 LAST BODY_TYPE PLUMBING
J 0
(-375 3425);
DISPLAY 0.872340 (-375 3425);
PAINT GREEN (-375 3425);
DISPLAY INVISIBLE (-375 3425);
FORCEPROP 1 LAST HDL_TAP TRUE
J 0
(-50 3250);
DISPLAY 0.872340 (-50 3250);
DISPLAY INVISIBLE (-50 3250);
FORCEPROP 1 LAST PATH I306
J 0
(-377 3375);
DISPLAY 0.872340 (-377 3375);
PAINT GREEN (-377 3375);
DISPLAY INVISIBLE (-377 3375);
FORCEADD TAP..1
(-375 3575);
FORCEPROP 3 LASTPIN (-425 3575) SIG_NAME P5E_CPU0_G3_TX_C_DN<15>
J 0
(-415 3585);
DISPLAY 0.659574 (-415 3585);
PAINT MONO (-415 3585);
DISPLAY INVISIBLE (-415 3585);
FORCEPROP 1 LASTPIN (-425 3575) BN 15
J 0
(-437 3583);
DISPLAY 0.680851 (-437 3583);
PAINT GREEN (-437 3583);
FORCEPROP 2 LAST CDS_LIB standard
J 0
(-375 3575);
DISPLAY INVISIBLE (-375 3575);
FORCEPROP 1 LAST BODY_TYPE PLUMBING
J 0
(-375 3625);
DISPLAY 0.872340 (-375 3625);
PAINT GREEN (-375 3625);
DISPLAY INVISIBLE (-375 3625);
FORCEPROP 1 LAST HDL_TAP TRUE
J 0
(-50 3450);
DISPLAY 0.872340 (-50 3450);
DISPLAY INVISIBLE (-50 3450);
FORCEPROP 1 LAST PATH I307
J 0
(-377 3575);
DISPLAY 0.872340 (-377 3575);
PAINT GREEN (-377 3575);
DISPLAY INVISIBLE (-377 3575);
FORCEADD TAP..1
(-175 3525);
FORCEPROP 3 LASTPIN (-225 3525) SIG_NAME P5E_CPU0_G3_TX_C_DP<15>
J 0
(-215 3535);
DISPLAY 0.659574 (-215 3535);
PAINT MONO (-215 3535);
DISPLAY INVISIBLE (-215 3535);
FORCEPROP 1 LASTPIN (-225 3525) BN 15
J 0
(-237 3533);
DISPLAY 0.680851 (-237 3533);
PAINT GREEN (-237 3533);
FORCEPROP 2 LAST CDS_LIB standard
J 0
(-175 3525);
DISPLAY INVISIBLE (-175 3525);
FORCEPROP 1 LAST BODY_TYPE PLUMBING
J 0
(-175 3575);
DISPLAY 0.872340 (-175 3575);
PAINT GREEN (-175 3575);
DISPLAY INVISIBLE (-175 3575);
FORCEPROP 1 LAST HDL_TAP TRUE
J 0
(150 3400);
DISPLAY 0.872340 (150 3400);
DISPLAY INVISIBLE (150 3400);
FORCEPROP 1 LAST PATH I308
J 0
(-177 3525);
DISPLAY 0.872340 (-177 3525);
PAINT GREEN (-177 3525);
DISPLAY INVISIBLE (-177 3525);
FORCEADD OFFPAGE..2
(825 3550);
FORCEPROP 2 LAST $XR0 131 
J 0
(1014 3550);
DISPLAY 0.638298 (1014 3550);
PAINT MONO (1014 3550);
FORCEPROP 2 LAST CDS_LIB standard
J 0
(825 3550);
DISPLAY INVISIBLE (825 3550);
FORCEPROP 1 LAST OFFPAGE TRUE
J 0
(1150 3425);
DISPLAY 0.872340 (1150 3425);
DISPLAY INVISIBLE (1150 3425);
FORCEPROP 1 LAST COMMENT_BODY TRUE
J 0
(780 3455);
DISPLAY 0.872340 (780 3455);
PAINT GREEN (780 3455);
DISPLAY INVISIBLE (780 3455);
FORCEPROP 2 LAST PATH I309
J 0
(1025 3600);
DISPLAY 1.021277 (1025 3600);
DISPLAY INVISIBLE (1025 3600);
FORCEADD OFFPAGE..2
(825 3600);
FORCEPROP 2 LAST $XR0 131 
J 0
(1014 3600);
DISPLAY 0.638298 (1014 3600);
PAINT MONO (1014 3600);
FORCEPROP 2 LAST CDS_LIB standard
J 0
(825 3600);
DISPLAY INVISIBLE (825 3600);
FORCEPROP 1 LAST OFFPAGE TRUE
J 0
(1150 3475);
DISPLAY 0.872340 (1150 3475);
DISPLAY INVISIBLE (1150 3475);
FORCEPROP 1 LAST COMMENT_BODY TRUE
J 0
(780 3505);
DISPLAY 0.872340 (780 3505);
PAINT GREEN (780 3505);
DISPLAY INVISIBLE (780 3505);
FORCEPROP 2 LAST PATH I310
J 0
(1025 3650);
DISPLAY 1.021277 (1025 3650);
DISPLAY INVISIBLE (1025 3650);
FORCEADD Q_CAP_DIFFBUS..2
R 2
(-925 350);
FORCEPROP 1 LAST LOCATION C1577
J 2
(-675 375);
DISPLAY 0.723404 (-675 375);
PAINT GREEN (-675 375);
FORCEPROP 2 LAST $SEC 1
J 2
(-750 425);
DISPLAY 0.680851 (-750 425);
PAINT MONO (-750 425);
DISPLAY INVISIBLE (-750 425);
FORCEPROP 2 LAST CDS_SEC 1
J 2
(-750 425);
DISPLAY 0.680851 (-750 425);
DISPLAY INVISIBLE (-750 425);
FORCEPROP 2 LASTPIN (-850 350) $PN 1
J 0
(-840 360);
DISPLAY 0.808511 (-840 360);
FORCEPROP 2 LASTPIN (-1000 350) $PN 2
J 2
(-1010 360);
DISPLAY 0.808511 (-1010 360);
FORCEPROP 2 LAST VALUE DIFF BUS_0.22UF
J 2
(-1075 350);
DISPLAY 0.553191 (-1075 350);
FORCEPROP 1 LAST PIN_NAMES_ROTATE TRUE
J 2
(-925 350);
DISPLAY 0.489362 (-925 350);
PAINT GREEN (-925 350);
DISPLAY INVISIBLE (-925 350);
FORCEPROP 2 LAST CDS_LIB pure_quanta
J 2
(-925 350);
DISPLAY INVISIBLE (-925 350);
FORCEPROP 1 LAST CDS_LMAN_SYM_OUTLINE -25,50,25,-50
J 2
(-925 350);
DISPLAY 0.468085 (-925 350);
PAINT GREEN (-925 350);
DISPLAY INVISIBLE (-925 350);
FORCEPROP 2 LAST VOLTAGE 6.3V
J 2
(-1275 400);
DISPLAY 0.553191 (-1275 400);
DISPLAY INVISIBLE (-1275 400);
FORCEPROP 1 LAST MATERIAL X6S
J 2
(-916 429);
DISPLAY 0.574468 (-916 429);
PAINT GREEN (-916 429);
DISPLAY INVISIBLE (-916 429);
FORCEPROP 2 LAST PACK_TYPE C0201
J 2
(-1100 400);
DISPLAY 0.553191 (-1100 400);
DISPLAY INVISIBLE (-1100 400);
FORCEPROP 2 LAST TOLERANCE 20%
J 2
(-1000 400);
DISPLAY 0.553191 (-1000 400);
DISPLAY INVISIBLE (-1000 400);
FORCEPROP 1 LAST PART_NUMBER SP_CH4221MEE01
J 2
(-1041 438);
DISPLAY 0.574468 (-1041 438);
PAINT GREEN (-1041 438);
DISPLAY INVISIBLE (-1041 438);
FORCEPROP 1 LAST PATH I311
J 2
(-925 350);
DISPLAY 0.723404 (-925 350);
DISPLAY INVISIBLE (-925 350);
FORCEADD Q_CAP_DIFFBUS..2
R 2
(-925 400);
FORCEPROP 1 LAST LOCATION C1576
J 2
(-675 425);
DISPLAY 0.723404 (-675 425);
PAINT GREEN (-675 425);
FORCEPROP 2 LAST $SEC 1
J 2
(-750 475);
DISPLAY 0.680851 (-750 475);
PAINT MONO (-750 475);
DISPLAY INVISIBLE (-750 475);
FORCEPROP 2 LAST CDS_SEC 1
J 2
(-750 475);
DISPLAY 0.680851 (-750 475);
DISPLAY INVISIBLE (-750 475);
FORCEPROP 2 LASTPIN (-850 400) $PN 1
J 0
(-840 410);
DISPLAY 0.808511 (-840 410);
FORCEPROP 2 LASTPIN (-1000 400) $PN 2
J 2
(-1010 410);
DISPLAY 0.808511 (-1010 410);
FORCEPROP 2 LAST VALUE DIFF BUS_0.22UF
J 2
(-1075 400);
DISPLAY 0.553191 (-1075 400);
FORCEPROP 1 LAST PIN_NAMES_ROTATE TRUE
J 2
(-925 400);
DISPLAY 0.489362 (-925 400);
PAINT GREEN (-925 400);
DISPLAY INVISIBLE (-925 400);
FORCEPROP 1 LAST CDS_LMAN_SYM_OUTLINE -25,50,25,-50
J 2
(-925 400);
DISPLAY 0.468085 (-925 400);
PAINT GREEN (-925 400);
DISPLAY INVISIBLE (-925 400);
FORCEPROP 2 LAST CDS_LIB pure_quanta
J 2
(-925 400);
DISPLAY INVISIBLE (-925 400);
FORCEPROP 2 LAST VOLTAGE 6.3V
J 2
(-1275 450);
DISPLAY 0.553191 (-1275 450);
DISPLAY INVISIBLE (-1275 450);
FORCEPROP 1 LAST MATERIAL X6S
J 2
(-916 479);
DISPLAY 0.574468 (-916 479);
PAINT GREEN (-916 479);
DISPLAY INVISIBLE (-916 479);
FORCEPROP 2 LAST PACK_TYPE C0201
J 2
(-1100 450);
DISPLAY 0.553191 (-1100 450);
DISPLAY INVISIBLE (-1100 450);
FORCEPROP 2 LAST TOLERANCE 20%
J 2
(-1000 450);
DISPLAY 0.553191 (-1000 450);
DISPLAY INVISIBLE (-1000 450);
FORCEPROP 1 LAST PART_NUMBER SP_CH4221MEE01
J 2
(-1041 488);
DISPLAY 0.574468 (-1041 488);
PAINT GREEN (-1041 488);
DISPLAY INVISIBLE (-1041 488);
FORCEPROP 1 LAST PATH I312
J 2
(-925 400);
DISPLAY 0.723404 (-925 400);
DISPLAY INVISIBLE (-925 400);
FORCEADD OFFPAGE..1
(1650 1625);
FORCEPROP 2 LAST $XR0 51 
J 0
(1429 1625);
DISPLAY 0.638298 (1429 1625);
PAINT MONO (1429 1625);
FORCEPROP 2 LAST CDS_LIB standard
J 0
(1650 1625);
DISPLAY INVISIBLE (1650 1625);
FORCEPROP 1 LAST OFFPAGE TRUE
J 0
(1975 1500);
DISPLAY 0.872340 (1975 1500);
DISPLAY INVISIBLE (1975 1500);
FORCEPROP 1 LAST COMMENT_BODY TRUE
J 0
(1775 1525);
DISPLAY 0.872340 (1775 1525);
PAINT GREEN (1775 1525);
DISPLAY INVISIBLE (1775 1525);
FORCEPROP 2 LAST PATH I313
J 0
(1375 1675);
DISPLAY 1.021277 (1375 1675);
DISPLAY INVISIBLE (1375 1675);
FORCEADD OFFPAGE..1
(1650 1575);
FORCEPROP 2 LAST $XR0 51 
J 0
(1429 1575);
DISPLAY 0.638298 (1429 1575);
PAINT MONO (1429 1575);
FORCEPROP 2 LAST CDS_LIB standard
J 0
(1650 1575);
DISPLAY INVISIBLE (1650 1575);
FORCEPROP 1 LAST OFFPAGE TRUE
J 0
(1975 1450);
DISPLAY 0.872340 (1975 1450);
DISPLAY INVISIBLE (1975 1450);
FORCEPROP 1 LAST COMMENT_BODY TRUE
J 0
(1775 1475);
DISPLAY 0.872340 (1775 1475);
PAINT GREEN (1775 1475);
DISPLAY INVISIBLE (1775 1475);
FORCEPROP 2 LAST PATH I314
J 0
(1375 1625);
DISPLAY 1.021277 (1375 1625);
DISPLAY INVISIBLE (1375 1625);
FORCEADD OFFPAGE..1
(1650 3550);
FORCEPROP 2 LAST $XR0 51 
J 0
(1429 3550);
DISPLAY 0.638298 (1429 3550);
PAINT MONO (1429 3550);
FORCEPROP 2 LAST CDS_LIB standard
J 0
(1650 3550);
DISPLAY INVISIBLE (1650 3550);
FORCEPROP 1 LAST OFFPAGE TRUE
J 0
(1975 3425);
DISPLAY 0.872340 (1975 3425);
DISPLAY INVISIBLE (1975 3425);
FORCEPROP 1 LAST COMMENT_BODY TRUE
J 0
(1775 3450);
DISPLAY 0.872340 (1775 3450);
PAINT GREEN (1775 3450);
DISPLAY INVISIBLE (1775 3450);
FORCEPROP 2 LAST PATH I315
J 0
(1375 3600);
DISPLAY 1.021277 (1375 3600);
DISPLAY INVISIBLE (1375 3600);
FORCEADD OFFPAGE..1
(1650 3600);
FORCEPROP 2 LAST $XR0 51 
J 0
(1429 3600);
DISPLAY 0.638298 (1429 3600);
PAINT MONO (1429 3600);
FORCEPROP 2 LAST CDS_LIB standard
J 0
(1650 3600);
DISPLAY INVISIBLE (1650 3600);
FORCEPROP 1 LAST OFFPAGE TRUE
J 0
(1975 3475);
DISPLAY 0.872340 (1975 3475);
DISPLAY INVISIBLE (1975 3475);
FORCEPROP 1 LAST COMMENT_BODY TRUE
J 0
(1775 3500);
DISPLAY 0.872340 (1775 3500);
PAINT GREEN (1775 3500);
DISPLAY INVISIBLE (1775 3500);
FORCEPROP 2 LAST PATH I316
J 0
(1375 3650);
DISPLAY 1.021277 (1375 3650);
DISPLAY INVISIBLE (1375 3650);
FORCEADD TAP..1
R 2
(2600 150);
FORCEPROP 3 LASTPIN (2650 150) SIG_NAME P5E_CPU1_P0_TX_DP<0>
J 0
(2660 160);
DISPLAY 0.659574 (2660 160);
PAINT MONO (2660 160);
DISPLAY INVISIBLE (2660 160);
FORCEPROP 1 LASTPIN (2650 150) BN 0
J 2
(2662 158);
DISPLAY 0.680851 (2662 158);
PAINT GREEN (2662 158);
FORCEPROP 2 LAST CDS_LIB standard
J 0
(2600 150);
DISPLAY INVISIBLE (2600 150);
FORCEPROP 1 LAST BODY_TYPE PLUMBING
J 2
(2600 200);
DISPLAY 0.872340 (2600 200);
PAINT GREEN (2600 200);
DISPLAY INVISIBLE (2600 200);
FORCEPROP 1 LAST HDL_TAP TRUE
J 2
(2275 25);
DISPLAY 0.872340 (2275 25);
DISPLAY INVISIBLE (2275 25);
FORCEPROP 1 LAST PATH I317
J 2
(2602 150);
DISPLAY 0.872340 (2602 150);
PAINT GREEN (2602 150);
DISPLAY INVISIBLE (2602 150);
FORCEADD TAP..1
R 2
(2600 350);
FORCEPROP 3 LASTPIN (2650 350) SIG_NAME P5E_CPU1_P0_TX_DP<1>
J 0
(2660 360);
DISPLAY 0.659574 (2660 360);
PAINT MONO (2660 360);
DISPLAY INVISIBLE (2660 360);
FORCEPROP 1 LASTPIN (2650 350) BN 1
J 2
(2662 358);
DISPLAY 0.680851 (2662 358);
PAINT GREEN (2662 358);
FORCEPROP 2 LAST CDS_LIB standard
J 0
(2600 350);
DISPLAY INVISIBLE (2600 350);
FORCEPROP 1 LAST BODY_TYPE PLUMBING
J 2
(2600 400);
DISPLAY 0.872340 (2600 400);
PAINT GREEN (2600 400);
DISPLAY INVISIBLE (2600 400);
FORCEPROP 1 LAST HDL_TAP TRUE
J 2
(2275 225);
DISPLAY 0.872340 (2275 225);
DISPLAY INVISIBLE (2275 225);
FORCEPROP 1 LAST PATH I318
J 2
(2602 350);
DISPLAY 0.872340 (2602 350);
PAINT GREEN (2602 350);
DISPLAY INVISIBLE (2602 350);
FORCEADD TAP..1
R 2
(2850 200);
FORCEPROP 3 LASTPIN (2900 200) SIG_NAME P5E_CPU1_P0_TX_DN<0>
J 0
(2910 210);
DISPLAY 0.659574 (2910 210);
PAINT MONO (2910 210);
DISPLAY INVISIBLE (2910 210);
FORCEPROP 1 LASTPIN (2900 200) BN 0
J 2
(2912 208);
DISPLAY 0.680851 (2912 208);
PAINT GREEN (2912 208);
FORCEPROP 2 LAST CDS_LIB standard
J 0
(2850 200);
DISPLAY INVISIBLE (2850 200);
FORCEPROP 1 LAST BODY_TYPE PLUMBING
J 2
(2850 250);
DISPLAY 0.872340 (2850 250);
PAINT GREEN (2850 250);
DISPLAY INVISIBLE (2850 250);
FORCEPROP 1 LAST HDL_TAP TRUE
J 2
(2525 75);
DISPLAY 0.872340 (2525 75);
DISPLAY INVISIBLE (2525 75);
FORCEPROP 1 LAST PATH I319
J 2
(2852 200);
DISPLAY 0.872340 (2852 200);
PAINT GREEN (2852 200);
DISPLAY INVISIBLE (2852 200);
FORCEADD TAP..1
R 2
(2850 400);
FORCEPROP 3 LASTPIN (2900 400) SIG_NAME P5E_CPU1_P0_TX_DN<1>
J 0
(2910 410);
DISPLAY 0.659574 (2910 410);
PAINT MONO (2910 410);
DISPLAY INVISIBLE (2910 410);
FORCEPROP 1 LASTPIN (2900 400) BN 1
J 2
(2912 408);
DISPLAY 0.680851 (2912 408);
PAINT GREEN (2912 408);
FORCEPROP 2 LAST CDS_LIB standard
J 0
(2850 400);
DISPLAY INVISIBLE (2850 400);
FORCEPROP 1 LAST BODY_TYPE PLUMBING
J 2
(2850 450);
DISPLAY 0.872340 (2850 450);
PAINT GREEN (2850 450);
DISPLAY INVISIBLE (2850 450);
FORCEPROP 1 LAST HDL_TAP TRUE
J 2
(2525 275);
DISPLAY 0.872340 (2525 275);
DISPLAY INVISIBLE (2525 275);
FORCEPROP 1 LAST PATH I320
J 2
(2852 400);
DISPLAY 0.872340 (2852 400);
PAINT GREEN (2852 400);
DISPLAY INVISIBLE (2852 400);
FORCEADD TAP..1
R 2
(2600 550);
FORCEPROP 3 LASTPIN (2650 550) SIG_NAME P5E_CPU1_P0_TX_DP<2>
J 0
(2660 560);
DISPLAY 0.659574 (2660 560);
PAINT MONO (2660 560);
DISPLAY INVISIBLE (2660 560);
FORCEPROP 1 LASTPIN (2650 550) BN 2
J 2
(2662 558);
DISPLAY 0.680851 (2662 558);
PAINT GREEN (2662 558);
FORCEPROP 2 LAST CDS_LIB standard
J 0
(2600 550);
DISPLAY INVISIBLE (2600 550);
FORCEPROP 1 LAST BODY_TYPE PLUMBING
J 2
(2600 600);
DISPLAY 0.872340 (2600 600);
PAINT GREEN (2600 600);
DISPLAY INVISIBLE (2600 600);
FORCEPROP 1 LAST HDL_TAP TRUE
J 2
(2275 425);
DISPLAY 0.872340 (2275 425);
DISPLAY INVISIBLE (2275 425);
FORCEPROP 1 LAST PATH I321
J 2
(2602 550);
DISPLAY 0.872340 (2602 550);
PAINT GREEN (2602 550);
DISPLAY INVISIBLE (2602 550);
FORCEADD TAP..1
R 2
(2600 750);
FORCEPROP 3 LASTPIN (2650 750) SIG_NAME P5E_CPU1_P0_TX_DP<3>
J 0
(2660 760);
DISPLAY 0.659574 (2660 760);
PAINT MONO (2660 760);
DISPLAY INVISIBLE (2660 760);
FORCEPROP 1 LASTPIN (2650 750) BN 3
J 2
(2662 758);
DISPLAY 0.680851 (2662 758);
PAINT GREEN (2662 758);
FORCEPROP 2 LAST CDS_LIB standard
J 0
(2600 750);
DISPLAY INVISIBLE (2600 750);
FORCEPROP 1 LAST BODY_TYPE PLUMBING
J 2
(2600 800);
DISPLAY 0.872340 (2600 800);
PAINT GREEN (2600 800);
DISPLAY INVISIBLE (2600 800);
FORCEPROP 1 LAST HDL_TAP TRUE
J 2
(2275 625);
DISPLAY 0.872340 (2275 625);
DISPLAY INVISIBLE (2275 625);
FORCEPROP 1 LAST PATH I322
J 2
(2602 750);
DISPLAY 0.872340 (2602 750);
PAINT GREEN (2602 750);
DISPLAY INVISIBLE (2602 750);
FORCEADD TAP..1
R 2
(2600 950);
FORCEPROP 3 LASTPIN (2650 950) SIG_NAME P5E_CPU1_P0_TX_DP<4>
J 0
(2660 960);
DISPLAY 0.659574 (2660 960);
PAINT MONO (2660 960);
DISPLAY INVISIBLE (2660 960);
FORCEPROP 1 LASTPIN (2650 950) BN 4
J 2
(2662 958);
DISPLAY 0.680851 (2662 958);
PAINT GREEN (2662 958);
FORCEPROP 2 LAST CDS_LIB standard
J 0
(2600 950);
DISPLAY INVISIBLE (2600 950);
FORCEPROP 1 LAST BODY_TYPE PLUMBING
J 2
(2600 1000);
DISPLAY 0.872340 (2600 1000);
PAINT GREEN (2600 1000);
DISPLAY INVISIBLE (2600 1000);
FORCEPROP 1 LAST HDL_TAP TRUE
J 2
(2275 825);
DISPLAY 0.872340 (2275 825);
DISPLAY INVISIBLE (2275 825);
FORCEPROP 1 LAST PATH I323
J 2
(2602 950);
DISPLAY 0.872340 (2602 950);
PAINT GREEN (2602 950);
DISPLAY INVISIBLE (2602 950);
FORCEADD TAP..1
R 2
(2850 600);
FORCEPROP 3 LASTPIN (2900 600) SIG_NAME P5E_CPU1_P0_TX_DN<2>
J 0
(2910 610);
DISPLAY 0.659574 (2910 610);
PAINT MONO (2910 610);
DISPLAY INVISIBLE (2910 610);
FORCEPROP 1 LASTPIN (2900 600) BN 2
J 2
(2912 608);
DISPLAY 0.680851 (2912 608);
PAINT GREEN (2912 608);
FORCEPROP 2 LAST CDS_LIB standard
J 0
(2850 600);
DISPLAY INVISIBLE (2850 600);
FORCEPROP 1 LAST BODY_TYPE PLUMBING
J 2
(2850 650);
DISPLAY 0.872340 (2850 650);
PAINT GREEN (2850 650);
DISPLAY INVISIBLE (2850 650);
FORCEPROP 1 LAST HDL_TAP TRUE
J 2
(2525 475);
DISPLAY 0.872340 (2525 475);
DISPLAY INVISIBLE (2525 475);
FORCEPROP 1 LAST PATH I324
J 2
(2852 600);
DISPLAY 0.872340 (2852 600);
PAINT GREEN (2852 600);
DISPLAY INVISIBLE (2852 600);
FORCEADD TAP..1
R 2
(2850 800);
FORCEPROP 3 LASTPIN (2900 800) SIG_NAME P5E_CPU1_P0_TX_DN<3>
J 0
(2910 810);
DISPLAY 0.659574 (2910 810);
PAINT MONO (2910 810);
DISPLAY INVISIBLE (2910 810);
FORCEPROP 1 LASTPIN (2900 800) BN 3
J 2
(2912 808);
DISPLAY 0.680851 (2912 808);
PAINT GREEN (2912 808);
FORCEPROP 2 LAST CDS_LIB standard
J 0
(2850 800);
DISPLAY INVISIBLE (2850 800);
FORCEPROP 1 LAST BODY_TYPE PLUMBING
J 2
(2850 850);
DISPLAY 0.872340 (2850 850);
PAINT GREEN (2850 850);
DISPLAY INVISIBLE (2850 850);
FORCEPROP 1 LAST HDL_TAP TRUE
J 2
(2525 675);
DISPLAY 0.872340 (2525 675);
DISPLAY INVISIBLE (2525 675);
FORCEPROP 1 LAST PATH I325
J 2
(2852 800);
DISPLAY 0.872340 (2852 800);
PAINT GREEN (2852 800);
DISPLAY INVISIBLE (2852 800);
FORCEADD TAP..1
R 2
(2850 1000);
FORCEPROP 3 LASTPIN (2900 1000) SIG_NAME P5E_CPU1_P0_TX_DN<4>
J 0
(2910 1010);
DISPLAY 0.659574 (2910 1010);
PAINT MONO (2910 1010);
DISPLAY INVISIBLE (2910 1010);
FORCEPROP 1 LASTPIN (2900 1000) BN 4
J 2
(2912 1008);
DISPLAY 0.680851 (2912 1008);
PAINT GREEN (2912 1008);
FORCEPROP 2 LAST CDS_LIB standard
J 0
(2850 1000);
DISPLAY INVISIBLE (2850 1000);
FORCEPROP 1 LAST BODY_TYPE PLUMBING
J 2
(2850 1050);
DISPLAY 0.872340 (2850 1050);
PAINT GREEN (2850 1050);
DISPLAY INVISIBLE (2850 1050);
FORCEPROP 1 LAST HDL_TAP TRUE
J 2
(2525 875);
DISPLAY 0.872340 (2525 875);
DISPLAY INVISIBLE (2525 875);
FORCEPROP 1 LAST PATH I326
J 2
(2852 1000);
DISPLAY 0.872340 (2852 1000);
PAINT GREEN (2852 1000);
DISPLAY INVISIBLE (2852 1000);
FORCEADD TAP..1
R 2
(2600 1150);
FORCEPROP 3 LASTPIN (2650 1150) SIG_NAME P5E_CPU1_P0_TX_DP<5>
J 0
(2660 1160);
DISPLAY 0.659574 (2660 1160);
PAINT MONO (2660 1160);
DISPLAY INVISIBLE (2660 1160);
FORCEPROP 1 LASTPIN (2650 1150) BN 5
J 2
(2662 1158);
DISPLAY 0.680851 (2662 1158);
PAINT GREEN (2662 1158);
FORCEPROP 2 LAST CDS_LIB standard
J 0
(2600 1150);
DISPLAY INVISIBLE (2600 1150);
FORCEPROP 1 LAST BODY_TYPE PLUMBING
J 2
(2600 1200);
DISPLAY 0.872340 (2600 1200);
PAINT GREEN (2600 1200);
DISPLAY INVISIBLE (2600 1200);
FORCEPROP 1 LAST HDL_TAP TRUE
J 2
(2275 1025);
DISPLAY 0.872340 (2275 1025);
DISPLAY INVISIBLE (2275 1025);
FORCEPROP 1 LAST PATH I327
J 2
(2602 1150);
DISPLAY 0.872340 (2602 1150);
PAINT GREEN (2602 1150);
DISPLAY INVISIBLE (2602 1150);
FORCEADD TAP..1
R 2
(2600 1350);
FORCEPROP 3 LASTPIN (2650 1350) SIG_NAME P5E_CPU1_P0_TX_DP<6>
J 0
(2660 1360);
DISPLAY 0.659574 (2660 1360);
PAINT MONO (2660 1360);
DISPLAY INVISIBLE (2660 1360);
FORCEPROP 1 LASTPIN (2650 1350) BN 6
J 2
(2662 1358);
DISPLAY 0.680851 (2662 1358);
PAINT GREEN (2662 1358);
FORCEPROP 2 LAST CDS_LIB standard
J 0
(2600 1350);
DISPLAY INVISIBLE (2600 1350);
FORCEPROP 1 LAST BODY_TYPE PLUMBING
J 2
(2600 1400);
DISPLAY 0.872340 (2600 1400);
PAINT GREEN (2600 1400);
DISPLAY INVISIBLE (2600 1400);
FORCEPROP 1 LAST HDL_TAP TRUE
J 2
(2275 1225);
DISPLAY 0.872340 (2275 1225);
DISPLAY INVISIBLE (2275 1225);
FORCEPROP 1 LAST PATH I328
J 2
(2602 1350);
DISPLAY 0.872340 (2602 1350);
PAINT GREEN (2602 1350);
DISPLAY INVISIBLE (2602 1350);
FORCEADD TAP..1
R 2
(2850 1200);
FORCEPROP 3 LASTPIN (2900 1200) SIG_NAME P5E_CPU1_P0_TX_DN<5>
J 0
(2910 1210);
DISPLAY 0.659574 (2910 1210);
PAINT MONO (2910 1210);
DISPLAY INVISIBLE (2910 1210);
FORCEPROP 1 LASTPIN (2900 1200) BN 5
J 2
(2912 1208);
DISPLAY 0.680851 (2912 1208);
PAINT GREEN (2912 1208);
FORCEPROP 2 LAST CDS_LIB standard
J 0
(2850 1200);
DISPLAY INVISIBLE (2850 1200);
FORCEPROP 1 LAST BODY_TYPE PLUMBING
J 2
(2850 1250);
DISPLAY 0.872340 (2850 1250);
PAINT GREEN (2850 1250);
DISPLAY INVISIBLE (2850 1250);
FORCEPROP 1 LAST HDL_TAP TRUE
J 2
(2525 1075);
DISPLAY 0.872340 (2525 1075);
DISPLAY INVISIBLE (2525 1075);
FORCEPROP 1 LAST PATH I329
J 2
(2852 1200);
DISPLAY 0.872340 (2852 1200);
PAINT GREEN (2852 1200);
DISPLAY INVISIBLE (2852 1200);
FORCEADD TAP..1
R 2
(2850 1400);
FORCEPROP 3 LASTPIN (2900 1400) SIG_NAME P5E_CPU1_P0_TX_DN<6>
J 0
(2910 1410);
DISPLAY 0.659574 (2910 1410);
PAINT MONO (2910 1410);
DISPLAY INVISIBLE (2910 1410);
FORCEPROP 1 LASTPIN (2900 1400) BN 6
J 2
(2912 1408);
DISPLAY 0.680851 (2912 1408);
PAINT GREEN (2912 1408);
FORCEPROP 2 LAST CDS_LIB standard
J 0
(2850 1400);
DISPLAY INVISIBLE (2850 1400);
FORCEPROP 1 LAST BODY_TYPE PLUMBING
J 2
(2850 1450);
DISPLAY 0.872340 (2850 1450);
PAINT GREEN (2850 1450);
DISPLAY INVISIBLE (2850 1450);
FORCEPROP 1 LAST HDL_TAP TRUE
J 2
(2525 1275);
DISPLAY 0.872340 (2525 1275);
DISPLAY INVISIBLE (2525 1275);
FORCEPROP 1 LAST PATH I330
J 2
(2852 1400);
DISPLAY 0.872340 (2852 1400);
PAINT GREEN (2852 1400);
DISPLAY INVISIBLE (2852 1400);
FORCEADD TAP..1
R 2
(2600 1550);
FORCEPROP 3 LASTPIN (2650 1550) SIG_NAME P5E_CPU1_P0_TX_DP<7>
J 0
(2660 1560);
DISPLAY 0.659574 (2660 1560);
PAINT MONO (2660 1560);
DISPLAY INVISIBLE (2660 1560);
FORCEPROP 1 LASTPIN (2650 1550) BN 7
J 2
(2662 1558);
DISPLAY 0.680851 (2662 1558);
PAINT GREEN (2662 1558);
FORCEPROP 2 LAST CDS_LIB standard
J 0
(2600 1550);
DISPLAY INVISIBLE (2600 1550);
FORCEPROP 1 LAST BODY_TYPE PLUMBING
J 2
(2600 1600);
DISPLAY 0.872340 (2600 1600);
PAINT GREEN (2600 1600);
DISPLAY INVISIBLE (2600 1600);
FORCEPROP 1 LAST HDL_TAP TRUE
J 2
(2275 1425);
DISPLAY 0.872340 (2275 1425);
DISPLAY INVISIBLE (2275 1425);
FORCEPROP 1 LAST PATH I331
J 2
(2602 1550);
DISPLAY 0.872340 (2602 1550);
PAINT GREEN (2602 1550);
DISPLAY INVISIBLE (2602 1550);
FORCEADD TAP..1
R 2
(2850 1600);
FORCEPROP 3 LASTPIN (2900 1600) SIG_NAME P5E_CPU1_P0_TX_DN<7>
J 0
(2910 1610);
DISPLAY 0.659574 (2910 1610);
PAINT MONO (2910 1610);
DISPLAY INVISIBLE (2910 1610);
FORCEPROP 1 LASTPIN (2900 1600) BN 7
J 2
(2912 1608);
DISPLAY 0.680851 (2912 1608);
PAINT GREEN (2912 1608);
FORCEPROP 2 LAST CDS_LIB standard
J 0
(2850 1600);
DISPLAY INVISIBLE (2850 1600);
FORCEPROP 1 LAST BODY_TYPE PLUMBING
J 2
(2850 1650);
DISPLAY 0.872340 (2850 1650);
PAINT GREEN (2850 1650);
DISPLAY INVISIBLE (2850 1650);
FORCEPROP 1 LAST HDL_TAP TRUE
J 2
(2525 1475);
DISPLAY 0.872340 (2525 1475);
DISPLAY INVISIBLE (2525 1475);
FORCEPROP 1 LAST PATH I332
J 2
(2852 1600);
DISPLAY 0.872340 (2852 1600);
PAINT GREEN (2852 1600);
DISPLAY INVISIBLE (2852 1600);
FORCEADD Q_CAP_DIFFBUS..2
R 2
(3575 200);
FORCEPROP 1 LAST LOCATION C836
J 2
(3809 217);
DISPLAY 0.723404 (3809 217);
PAINT GREEN (3809 217);
FORCEPROP 2 LAST $SEC 1
J 2
(3750 275);
DISPLAY 0.680851 (3750 275);
PAINT MONO (3750 275);
DISPLAY INVISIBLE (3750 275);
FORCEPROP 2 LAST CDS_SEC 1
J 2
(3750 275);
DISPLAY 0.680851 (3750 275);
DISPLAY INVISIBLE (3750 275);
FORCEPROP 2 LASTPIN (3650 200) $PN 1
J 0
(3660 210);
DISPLAY 0.808511 (3660 210);
FORCEPROP 2 LASTPIN (3500 200) $PN 2
J 2
(3490 210);
DISPLAY 0.808511 (3490 210);
FORCEPROP 2 LAST VALUE DIFF BUS_0.22UF
J 2
(3425 200);
DISPLAY 0.553191 (3425 200);
FORCEPROP 1 LAST PIN_NAMES_ROTATE TRUE
J 2
(3575 200);
DISPLAY 0.489362 (3575 200);
PAINT GREEN (3575 200);
DISPLAY INVISIBLE (3575 200);
FORCEPROP 2 LAST CDS_LIB pure_quanta
J 2
(3575 200);
DISPLAY INVISIBLE (3575 200);
FORCEPROP 1 LAST CDS_LMAN_SYM_OUTLINE -25,50,25,-50
J 2
(3575 200);
DISPLAY 0.468085 (3575 200);
PAINT GREEN (3575 200);
DISPLAY INVISIBLE (3575 200);
FORCEPROP 2 LAST VOLTAGE 6.3V
J 2
(3225 250);
DISPLAY 0.553191 (3225 250);
DISPLAY INVISIBLE (3225 250);
FORCEPROP 1 LAST MATERIAL X6S
J 2
(3584 279);
DISPLAY 0.574468 (3584 279);
PAINT GREEN (3584 279);
DISPLAY INVISIBLE (3584 279);
FORCEPROP 2 LAST PACK_TYPE C0201
J 2
(3400 250);
DISPLAY 0.553191 (3400 250);
DISPLAY INVISIBLE (3400 250);
FORCEPROP 2 LAST TOLERANCE 20%
J 2
(3500 250);
DISPLAY 0.553191 (3500 250);
DISPLAY INVISIBLE (3500 250);
FORCEPROP 1 LAST PART_NUMBER SP_CH4221MEE01
J 2
(3459 288);
DISPLAY 0.574468 (3459 288);
PAINT GREEN (3459 288);
DISPLAY INVISIBLE (3459 288);
FORCEPROP 1 LAST LOCATION C836
J 0
(3825 275);
DISPLAY 1.021277 (3825 275);
DISPLAY INVISIBLE (3825 275);
FORCEPROP 1 LAST PATH I333
J 2
(3575 200);
DISPLAY 0.723404 (3575 200);
DISPLAY INVISIBLE (3575 200);
FORCEADD Q_CAP_DIFFBUS..2
R 2
(3575 150);
FORCEPROP 1 LAST LOCATION C837
J 2
(3809 167);
DISPLAY 0.723404 (3809 167);
PAINT GREEN (3809 167);
FORCEPROP 2 LAST $SEC 1
J 2
(3750 225);
DISPLAY 0.680851 (3750 225);
PAINT MONO (3750 225);
DISPLAY INVISIBLE (3750 225);
FORCEPROP 2 LAST CDS_SEC 1
J 2
(3750 225);
DISPLAY 0.680851 (3750 225);
DISPLAY INVISIBLE (3750 225);
FORCEPROP 2 LASTPIN (3650 150) $PN 1
J 0
(3660 160);
DISPLAY 0.808511 (3660 160);
FORCEPROP 2 LASTPIN (3500 150) $PN 2
J 2
(3490 160);
DISPLAY 0.808511 (3490 160);
FORCEPROP 2 LAST VALUE DIFF BUS_0.22UF
J 2
(3425 150);
DISPLAY 0.553191 (3425 150);
FORCEPROP 1 LAST PIN_NAMES_ROTATE TRUE
J 2
(3575 150);
DISPLAY 0.489362 (3575 150);
PAINT GREEN (3575 150);
DISPLAY INVISIBLE (3575 150);
FORCEPROP 2 LAST CDS_LIB pure_quanta
J 2
(3575 150);
DISPLAY INVISIBLE (3575 150);
FORCEPROP 1 LAST CDS_LMAN_SYM_OUTLINE -25,50,25,-50
J 2
(3575 150);
DISPLAY 0.468085 (3575 150);
PAINT GREEN (3575 150);
DISPLAY INVISIBLE (3575 150);
FORCEPROP 2 LAST VOLTAGE 6.3V
J 2
(3225 200);
DISPLAY 0.553191 (3225 200);
DISPLAY INVISIBLE (3225 200);
FORCEPROP 1 LAST MATERIAL X6S
J 2
(3584 229);
DISPLAY 0.574468 (3584 229);
PAINT GREEN (3584 229);
DISPLAY INVISIBLE (3584 229);
FORCEPROP 2 LAST PACK_TYPE C0201
J 2
(3400 200);
DISPLAY 0.553191 (3400 200);
DISPLAY INVISIBLE (3400 200);
FORCEPROP 2 LAST TOLERANCE 20%
J 2
(3500 200);
DISPLAY 0.553191 (3500 200);
DISPLAY INVISIBLE (3500 200);
FORCEPROP 1 LAST PART_NUMBER SP_CH4221MEE01
J 2
(3459 238);
DISPLAY 0.574468 (3459 238);
PAINT GREEN (3459 238);
DISPLAY INVISIBLE (3459 238);
FORCEPROP 1 LAST LOCATION C837
J 0
(3825 225);
DISPLAY 1.021277 (3825 225);
DISPLAY INVISIBLE (3825 225);
FORCEPROP 1 LAST PATH I334
J 2
(3575 150);
DISPLAY 0.723404 (3575 150);
DISPLAY INVISIBLE (3575 150);
FORCEADD Q_CAP_DIFFBUS..2
R 2
(3575 400);
FORCEPROP 1 LAST LOCATION C834
J 2
(3809 417);
DISPLAY 0.723404 (3809 417);
PAINT GREEN (3809 417);
FORCEPROP 2 LAST $SEC 1
J 2
(3750 475);
DISPLAY 0.680851 (3750 475);
PAINT MONO (3750 475);
DISPLAY INVISIBLE (3750 475);
FORCEPROP 2 LAST CDS_SEC 1
J 2
(3750 475);
DISPLAY 0.680851 (3750 475);
DISPLAY INVISIBLE (3750 475);
FORCEPROP 2 LASTPIN (3650 400) $PN 1
J 0
(3660 410);
DISPLAY 0.808511 (3660 410);
FORCEPROP 2 LASTPIN (3500 400) $PN 2
J 2
(3490 410);
DISPLAY 0.808511 (3490 410);
FORCEPROP 2 LAST VALUE DIFF BUS_0.22UF
J 2
(3425 400);
DISPLAY 0.553191 (3425 400);
FORCEPROP 1 LAST PIN_NAMES_ROTATE TRUE
J 2
(3575 400);
DISPLAY 0.489362 (3575 400);
PAINT GREEN (3575 400);
DISPLAY INVISIBLE (3575 400);
FORCEPROP 1 LAST CDS_LMAN_SYM_OUTLINE -25,50,25,-50
J 2
(3575 400);
DISPLAY 0.468085 (3575 400);
PAINT GREEN (3575 400);
DISPLAY INVISIBLE (3575 400);
FORCEPROP 2 LAST CDS_LIB pure_quanta
J 2
(3575 400);
DISPLAY INVISIBLE (3575 400);
FORCEPROP 2 LAST VOLTAGE 6.3V
J 2
(3225 450);
DISPLAY 0.553191 (3225 450);
DISPLAY INVISIBLE (3225 450);
FORCEPROP 1 LAST MATERIAL X6S
J 2
(3584 479);
DISPLAY 0.574468 (3584 479);
PAINT GREEN (3584 479);
DISPLAY INVISIBLE (3584 479);
FORCEPROP 2 LAST PACK_TYPE C0201
J 2
(3400 450);
DISPLAY 0.553191 (3400 450);
DISPLAY INVISIBLE (3400 450);
FORCEPROP 2 LAST TOLERANCE 20%
J 2
(3500 450);
DISPLAY 0.553191 (3500 450);
DISPLAY INVISIBLE (3500 450);
FORCEPROP 1 LAST PART_NUMBER SP_CH4221MEE01
J 2
(3459 488);
DISPLAY 0.574468 (3459 488);
PAINT GREEN (3459 488);
DISPLAY INVISIBLE (3459 488);
FORCEPROP 1 LAST LOCATION C834
J 0
(3825 475);
DISPLAY 1.021277 (3825 475);
DISPLAY INVISIBLE (3825 475);
FORCEPROP 1 LAST PATH I335
J 2
(3575 400);
DISPLAY 0.723404 (3575 400);
DISPLAY INVISIBLE (3575 400);
FORCEADD Q_CAP_DIFFBUS..2
R 2
(3575 350);
FORCEPROP 1 LAST LOCATION C835
J 2
(3809 367);
DISPLAY 0.723404 (3809 367);
PAINT GREEN (3809 367);
FORCEPROP 2 LAST $SEC 1
J 2
(3750 425);
DISPLAY 0.680851 (3750 425);
PAINT MONO (3750 425);
DISPLAY INVISIBLE (3750 425);
FORCEPROP 2 LAST CDS_SEC 1
J 2
(3750 425);
DISPLAY 0.680851 (3750 425);
DISPLAY INVISIBLE (3750 425);
FORCEPROP 2 LASTPIN (3650 350) $PN 1
J 0
(3660 360);
DISPLAY 0.808511 (3660 360);
FORCEPROP 2 LASTPIN (3500 350) $PN 2
J 2
(3490 360);
DISPLAY 0.808511 (3490 360);
FORCEPROP 2 LAST VALUE DIFF BUS_0.22UF
J 2
(3425 350);
DISPLAY 0.553191 (3425 350);
FORCEPROP 1 LAST PIN_NAMES_ROTATE TRUE
J 2
(3575 350);
DISPLAY 0.489362 (3575 350);
PAINT GREEN (3575 350);
DISPLAY INVISIBLE (3575 350);
FORCEPROP 2 LAST CDS_LIB pure_quanta
J 2
(3575 350);
DISPLAY INVISIBLE (3575 350);
FORCEPROP 1 LAST CDS_LMAN_SYM_OUTLINE -25,50,25,-50
J 2
(3575 350);
DISPLAY 0.468085 (3575 350);
PAINT GREEN (3575 350);
DISPLAY INVISIBLE (3575 350);
FORCEPROP 2 LAST VOLTAGE 6.3V
J 2
(3225 400);
DISPLAY 0.553191 (3225 400);
DISPLAY INVISIBLE (3225 400);
FORCEPROP 1 LAST MATERIAL X6S
J 2
(3584 429);
DISPLAY 0.574468 (3584 429);
PAINT GREEN (3584 429);
DISPLAY INVISIBLE (3584 429);
FORCEPROP 2 LAST PACK_TYPE C0201
J 2
(3400 400);
DISPLAY 0.553191 (3400 400);
DISPLAY INVISIBLE (3400 400);
FORCEPROP 2 LAST TOLERANCE 20%
J 2
(3500 400);
DISPLAY 0.553191 (3500 400);
DISPLAY INVISIBLE (3500 400);
FORCEPROP 1 LAST PART_NUMBER SP_CH4221MEE01
J 2
(3459 438);
DISPLAY 0.574468 (3459 438);
PAINT GREEN (3459 438);
DISPLAY INVISIBLE (3459 438);
FORCEPROP 1 LAST LOCATION C835
J 0
(3825 425);
DISPLAY 1.021277 (3825 425);
DISPLAY INVISIBLE (3825 425);
FORCEPROP 1 LAST PATH I336
J 2
(3575 350);
DISPLAY 0.723404 (3575 350);
DISPLAY INVISIBLE (3575 350);
FORCEADD Q_CAP_DIFFBUS..2
R 2
(3575 750);
FORCEPROP 1 LAST LOCATION C831
J 2
(3809 767);
DISPLAY 0.723404 (3809 767);
PAINT GREEN (3809 767);
FORCEPROP 2 LAST $SEC 1
J 2
(3750 825);
DISPLAY 0.680851 (3750 825);
PAINT MONO (3750 825);
DISPLAY INVISIBLE (3750 825);
FORCEPROP 2 LAST CDS_SEC 1
J 2
(3750 825);
DISPLAY 0.680851 (3750 825);
DISPLAY INVISIBLE (3750 825);
FORCEPROP 2 LASTPIN (3650 750) $PN 1
J 0
(3660 760);
DISPLAY 0.808511 (3660 760);
FORCEPROP 2 LASTPIN (3500 750) $PN 2
J 2
(3490 760);
DISPLAY 0.808511 (3490 760);
FORCEPROP 2 LAST VALUE DIFF BUS_0.22UF
J 2
(3425 750);
DISPLAY 0.553191 (3425 750);
FORCEPROP 1 LAST PIN_NAMES_ROTATE TRUE
J 2
(3575 750);
DISPLAY 0.489362 (3575 750);
PAINT GREEN (3575 750);
DISPLAY INVISIBLE (3575 750);
FORCEPROP 1 LAST CDS_LMAN_SYM_OUTLINE -25,50,25,-50
J 2
(3575 750);
DISPLAY 0.468085 (3575 750);
PAINT GREEN (3575 750);
DISPLAY INVISIBLE (3575 750);
FORCEPROP 2 LAST CDS_LIB pure_quanta
J 2
(3575 750);
DISPLAY INVISIBLE (3575 750);
FORCEPROP 2 LAST VOLTAGE 6.3V
J 2
(3225 800);
DISPLAY 0.553191 (3225 800);
DISPLAY INVISIBLE (3225 800);
FORCEPROP 1 LAST MATERIAL X6S
J 2
(3584 829);
DISPLAY 0.574468 (3584 829);
PAINT GREEN (3584 829);
DISPLAY INVISIBLE (3584 829);
FORCEPROP 2 LAST PACK_TYPE C0201
J 2
(3400 800);
DISPLAY 0.553191 (3400 800);
DISPLAY INVISIBLE (3400 800);
FORCEPROP 2 LAST TOLERANCE 20%
J 2
(3500 800);
DISPLAY 0.553191 (3500 800);
DISPLAY INVISIBLE (3500 800);
FORCEPROP 1 LAST PART_NUMBER SP_CH4221MEE01
J 2
(3459 838);
DISPLAY 0.574468 (3459 838);
PAINT GREEN (3459 838);
DISPLAY INVISIBLE (3459 838);
FORCEPROP 1 LAST LOCATION C831
J 0
(3825 825);
DISPLAY 1.021277 (3825 825);
DISPLAY INVISIBLE (3825 825);
FORCEPROP 1 LAST PATH I337
J 2
(3575 750);
DISPLAY 0.723404 (3575 750);
DISPLAY INVISIBLE (3575 750);
FORCEADD Q_CAP_DIFFBUS..2
R 2
(3575 600);
FORCEPROP 1 LAST LOCATION C832
J 2
(3809 617);
DISPLAY 0.723404 (3809 617);
PAINT GREEN (3809 617);
FORCEPROP 2 LAST $SEC 1
J 2
(3750 675);
DISPLAY 0.680851 (3750 675);
PAINT MONO (3750 675);
DISPLAY INVISIBLE (3750 675);
FORCEPROP 2 LAST CDS_SEC 1
J 2
(3750 675);
DISPLAY 0.680851 (3750 675);
DISPLAY INVISIBLE (3750 675);
FORCEPROP 2 LASTPIN (3650 600) $PN 1
J 0
(3660 610);
DISPLAY 0.808511 (3660 610);
FORCEPROP 2 LASTPIN (3500 600) $PN 2
J 2
(3490 610);
DISPLAY 0.808511 (3490 610);
FORCEPROP 2 LAST VALUE DIFF BUS_0.22UF
J 2
(3425 600);
DISPLAY 0.553191 (3425 600);
FORCEPROP 1 LAST PIN_NAMES_ROTATE TRUE
J 2
(3575 600);
DISPLAY 0.489362 (3575 600);
PAINT GREEN (3575 600);
DISPLAY INVISIBLE (3575 600);
FORCEPROP 2 LAST CDS_LIB pure_quanta
J 2
(3575 600);
DISPLAY INVISIBLE (3575 600);
FORCEPROP 1 LAST CDS_LMAN_SYM_OUTLINE -25,50,25,-50
J 2
(3575 600);
DISPLAY 0.468085 (3575 600);
PAINT GREEN (3575 600);
DISPLAY INVISIBLE (3575 600);
FORCEPROP 2 LAST VOLTAGE 6.3V
J 2
(3225 650);
DISPLAY 0.553191 (3225 650);
DISPLAY INVISIBLE (3225 650);
FORCEPROP 1 LAST MATERIAL X6S
J 2
(3584 679);
DISPLAY 0.574468 (3584 679);
PAINT GREEN (3584 679);
DISPLAY INVISIBLE (3584 679);
FORCEPROP 2 LAST PACK_TYPE C0201
J 2
(3400 650);
DISPLAY 0.553191 (3400 650);
DISPLAY INVISIBLE (3400 650);
FORCEPROP 2 LAST TOLERANCE 20%
J 2
(3500 650);
DISPLAY 0.553191 (3500 650);
DISPLAY INVISIBLE (3500 650);
FORCEPROP 1 LAST PART_NUMBER SP_CH4221MEE01
J 2
(3459 688);
DISPLAY 0.574468 (3459 688);
PAINT GREEN (3459 688);
DISPLAY INVISIBLE (3459 688);
FORCEPROP 1 LAST LOCATION C832
J 0
(3825 675);
DISPLAY 1.021277 (3825 675);
DISPLAY INVISIBLE (3825 675);
FORCEPROP 1 LAST PATH I338
J 2
(3575 600);
DISPLAY 0.723404 (3575 600);
DISPLAY INVISIBLE (3575 600);
FORCEADD Q_CAP_DIFFBUS..2
R 2
(3575 550);
FORCEPROP 1 LAST LOCATION C833
J 2
(3809 567);
DISPLAY 0.723404 (3809 567);
PAINT GREEN (3809 567);
FORCEPROP 2 LAST $SEC 1
J 2
(3750 625);
DISPLAY 0.680851 (3750 625);
PAINT MONO (3750 625);
DISPLAY INVISIBLE (3750 625);
FORCEPROP 2 LAST CDS_SEC 1
J 2
(3750 625);
DISPLAY 0.680851 (3750 625);
DISPLAY INVISIBLE (3750 625);
FORCEPROP 2 LASTPIN (3650 550) $PN 1
J 0
(3660 560);
DISPLAY 0.808511 (3660 560);
FORCEPROP 2 LASTPIN (3500 550) $PN 2
J 2
(3490 560);
DISPLAY 0.808511 (3490 560);
FORCEPROP 2 LAST VALUE DIFF BUS_0.22UF
J 2
(3425 550);
DISPLAY 0.553191 (3425 550);
FORCEPROP 1 LAST PIN_NAMES_ROTATE TRUE
J 2
(3575 550);
DISPLAY 0.489362 (3575 550);
PAINT GREEN (3575 550);
DISPLAY INVISIBLE (3575 550);
FORCEPROP 2 LAST CDS_LIB pure_quanta
J 2
(3575 550);
DISPLAY INVISIBLE (3575 550);
FORCEPROP 1 LAST CDS_LMAN_SYM_OUTLINE -25,50,25,-50
J 2
(3575 550);
DISPLAY 0.468085 (3575 550);
PAINT GREEN (3575 550);
DISPLAY INVISIBLE (3575 550);
FORCEPROP 2 LAST VOLTAGE 6.3V
J 2
(3225 600);
DISPLAY 0.553191 (3225 600);
DISPLAY INVISIBLE (3225 600);
FORCEPROP 1 LAST MATERIAL X6S
J 2
(3584 629);
DISPLAY 0.574468 (3584 629);
PAINT GREEN (3584 629);
DISPLAY INVISIBLE (3584 629);
FORCEPROP 2 LAST PACK_TYPE C0201
J 2
(3400 600);
DISPLAY 0.553191 (3400 600);
DISPLAY INVISIBLE (3400 600);
FORCEPROP 2 LAST TOLERANCE 20%
J 2
(3500 600);
DISPLAY 0.553191 (3500 600);
DISPLAY INVISIBLE (3500 600);
FORCEPROP 1 LAST PART_NUMBER SP_CH4221MEE01
J 2
(3459 638);
DISPLAY 0.574468 (3459 638);
PAINT GREEN (3459 638);
DISPLAY INVISIBLE (3459 638);
FORCEPROP 1 LAST LOCATION C833
J 0
(3825 625);
DISPLAY 1.021277 (3825 625);
DISPLAY INVISIBLE (3825 625);
FORCEPROP 1 LAST PATH I339
J 2
(3575 550);
DISPLAY 0.723404 (3575 550);
DISPLAY INVISIBLE (3575 550);
FORCEADD Q_CAP_DIFFBUS..2
R 2
(3575 1000);
FORCEPROP 1 LAST LOCATION C828
J 2
(3809 1017);
DISPLAY 0.723404 (3809 1017);
PAINT GREEN (3809 1017);
FORCEPROP 2 LAST $SEC 1
J 2
(3750 1075);
DISPLAY 0.680851 (3750 1075);
PAINT MONO (3750 1075);
DISPLAY INVISIBLE (3750 1075);
FORCEPROP 2 LAST CDS_SEC 1
J 2
(3750 1075);
DISPLAY 0.680851 (3750 1075);
DISPLAY INVISIBLE (3750 1075);
FORCEPROP 2 LASTPIN (3650 1000) $PN 1
J 0
(3660 1010);
DISPLAY 0.808511 (3660 1010);
FORCEPROP 2 LASTPIN (3500 1000) $PN 2
J 2
(3490 1010);
DISPLAY 0.808511 (3490 1010);
FORCEPROP 2 LAST VALUE DIFF BUS_0.22UF
J 2
(3425 1000);
DISPLAY 0.553191 (3425 1000);
FORCEPROP 1 LAST PIN_NAMES_ROTATE TRUE
J 2
(3575 1000);
DISPLAY 0.489362 (3575 1000);
PAINT GREEN (3575 1000);
DISPLAY INVISIBLE (3575 1000);
FORCEPROP 2 LAST CDS_LIB pure_quanta
J 2
(3575 1000);
DISPLAY INVISIBLE (3575 1000);
FORCEPROP 1 LAST CDS_LMAN_SYM_OUTLINE -25,50,25,-50
J 2
(3575 1000);
DISPLAY 0.468085 (3575 1000);
PAINT GREEN (3575 1000);
DISPLAY INVISIBLE (3575 1000);
FORCEPROP 2 LAST VOLTAGE 6.3V
J 2
(3225 1050);
DISPLAY 0.553191 (3225 1050);
DISPLAY INVISIBLE (3225 1050);
FORCEPROP 1 LAST MATERIAL X6S
J 2
(3584 1079);
DISPLAY 0.574468 (3584 1079);
PAINT GREEN (3584 1079);
DISPLAY INVISIBLE (3584 1079);
FORCEPROP 2 LAST PACK_TYPE C0201
J 2
(3400 1050);
DISPLAY 0.553191 (3400 1050);
DISPLAY INVISIBLE (3400 1050);
FORCEPROP 2 LAST TOLERANCE 20%
J 2
(3500 1050);
DISPLAY 0.553191 (3500 1050);
DISPLAY INVISIBLE (3500 1050);
FORCEPROP 1 LAST PART_NUMBER SP_CH4221MEE01
J 2
(3459 1088);
DISPLAY 0.574468 (3459 1088);
PAINT GREEN (3459 1088);
DISPLAY INVISIBLE (3459 1088);
FORCEPROP 1 LAST LOCATION C828
J 0
(3825 1075);
DISPLAY 1.021277 (3825 1075);
DISPLAY INVISIBLE (3825 1075);
FORCEPROP 1 LAST PATH I340
J 2
(3575 1000);
DISPLAY 0.723404 (3575 1000);
DISPLAY INVISIBLE (3575 1000);
FORCEADD Q_CAP_DIFFBUS..2
R 2
(3575 800);
FORCEPROP 1 LAST LOCATION C830
J 2
(3809 817);
DISPLAY 0.723404 (3809 817);
PAINT GREEN (3809 817);
FORCEPROP 2 LAST $SEC 1
J 2
(3750 875);
DISPLAY 0.680851 (3750 875);
PAINT MONO (3750 875);
DISPLAY INVISIBLE (3750 875);
FORCEPROP 2 LAST CDS_SEC 1
J 2
(3750 875);
DISPLAY 0.680851 (3750 875);
DISPLAY INVISIBLE (3750 875);
FORCEPROP 2 LASTPIN (3650 800) $PN 1
J 0
(3660 810);
DISPLAY 0.808511 (3660 810);
FORCEPROP 2 LASTPIN (3500 800) $PN 2
J 2
(3490 810);
DISPLAY 0.808511 (3490 810);
FORCEPROP 2 LAST VALUE DIFF BUS_0.22UF
J 2
(3425 800);
DISPLAY 0.553191 (3425 800);
FORCEPROP 1 LAST PIN_NAMES_ROTATE TRUE
J 2
(3575 800);
DISPLAY 0.489362 (3575 800);
PAINT GREEN (3575 800);
DISPLAY INVISIBLE (3575 800);
FORCEPROP 1 LAST CDS_LMAN_SYM_OUTLINE -25,50,25,-50
J 2
(3575 800);
DISPLAY 0.468085 (3575 800);
PAINT GREEN (3575 800);
DISPLAY INVISIBLE (3575 800);
FORCEPROP 2 LAST CDS_LIB pure_quanta
J 2
(3575 800);
DISPLAY INVISIBLE (3575 800);
FORCEPROP 2 LAST VOLTAGE 6.3V
J 2
(3225 850);
DISPLAY 0.553191 (3225 850);
DISPLAY INVISIBLE (3225 850);
FORCEPROP 1 LAST MATERIAL X6S
J 2
(3584 879);
DISPLAY 0.574468 (3584 879);
PAINT GREEN (3584 879);
DISPLAY INVISIBLE (3584 879);
FORCEPROP 2 LAST PACK_TYPE C0201
J 2
(3400 850);
DISPLAY 0.553191 (3400 850);
DISPLAY INVISIBLE (3400 850);
FORCEPROP 2 LAST TOLERANCE 20%
J 2
(3500 850);
DISPLAY 0.553191 (3500 850);
DISPLAY INVISIBLE (3500 850);
FORCEPROP 1 LAST PART_NUMBER SP_CH4221MEE01
J 2
(3459 888);
DISPLAY 0.574468 (3459 888);
PAINT GREEN (3459 888);
DISPLAY INVISIBLE (3459 888);
FORCEPROP 1 LAST LOCATION C830
J 0
(3825 875);
DISPLAY 1.021277 (3825 875);
DISPLAY INVISIBLE (3825 875);
FORCEPROP 1 LAST PATH I341
J 2
(3575 800);
DISPLAY 0.723404 (3575 800);
DISPLAY INVISIBLE (3575 800);
FORCEADD Q_CAP_DIFFBUS..2
R 2
(3575 950);
FORCEPROP 1 LAST LOCATION C829
J 2
(3809 967);
DISPLAY 0.723404 (3809 967);
PAINT GREEN (3809 967);
FORCEPROP 2 LAST $SEC 1
J 2
(3750 1025);
DISPLAY 0.680851 (3750 1025);
PAINT MONO (3750 1025);
DISPLAY INVISIBLE (3750 1025);
FORCEPROP 2 LAST CDS_SEC 1
J 2
(3750 1025);
DISPLAY 0.680851 (3750 1025);
DISPLAY INVISIBLE (3750 1025);
FORCEPROP 2 LASTPIN (3650 950) $PN 1
J 0
(3660 960);
DISPLAY 0.808511 (3660 960);
FORCEPROP 2 LASTPIN (3500 950) $PN 2
J 2
(3490 960);
DISPLAY 0.808511 (3490 960);
FORCEPROP 2 LAST VALUE DIFF BUS_0.22UF
J 2
(3425 950);
DISPLAY 0.553191 (3425 950);
FORCEPROP 1 LAST PIN_NAMES_ROTATE TRUE
J 2
(3575 950);
DISPLAY 0.489362 (3575 950);
PAINT GREEN (3575 950);
DISPLAY INVISIBLE (3575 950);
FORCEPROP 2 LAST CDS_LIB pure_quanta
J 2
(3575 950);
DISPLAY INVISIBLE (3575 950);
FORCEPROP 1 LAST CDS_LMAN_SYM_OUTLINE -25,50,25,-50
J 2
(3575 950);
DISPLAY 0.468085 (3575 950);
PAINT GREEN (3575 950);
DISPLAY INVISIBLE (3575 950);
FORCEPROP 2 LAST VOLTAGE 6.3V
J 2
(3225 1000);
DISPLAY 0.553191 (3225 1000);
DISPLAY INVISIBLE (3225 1000);
FORCEPROP 1 LAST MATERIAL X6S
J 2
(3584 1029);
DISPLAY 0.574468 (3584 1029);
PAINT GREEN (3584 1029);
DISPLAY INVISIBLE (3584 1029);
FORCEPROP 2 LAST PACK_TYPE C0201
J 2
(3400 1000);
DISPLAY 0.553191 (3400 1000);
DISPLAY INVISIBLE (3400 1000);
FORCEPROP 2 LAST TOLERANCE 20%
J 2
(3500 1000);
DISPLAY 0.553191 (3500 1000);
DISPLAY INVISIBLE (3500 1000);
FORCEPROP 1 LAST PART_NUMBER SP_CH4221MEE01
J 2
(3459 1038);
DISPLAY 0.574468 (3459 1038);
PAINT GREEN (3459 1038);
DISPLAY INVISIBLE (3459 1038);
FORCEPROP 1 LAST LOCATION C829
J 0
(3825 1025);
DISPLAY 1.021277 (3825 1025);
DISPLAY INVISIBLE (3825 1025);
FORCEPROP 1 LAST PATH I342
J 2
(3575 950);
DISPLAY 0.723404 (3575 950);
DISPLAY INVISIBLE (3575 950);
FORCEADD Q_CAP_DIFFBUS..2
R 2
(3575 1150);
FORCEPROP 1 LAST LOCATION C827
J 2
(3809 1167);
DISPLAY 0.723404 (3809 1167);
PAINT GREEN (3809 1167);
FORCEPROP 2 LAST $SEC 1
J 2
(3750 1225);
DISPLAY 0.680851 (3750 1225);
PAINT MONO (3750 1225);
DISPLAY INVISIBLE (3750 1225);
FORCEPROP 2 LAST CDS_SEC 1
J 2
(3750 1225);
DISPLAY 0.680851 (3750 1225);
DISPLAY INVISIBLE (3750 1225);
FORCEPROP 2 LASTPIN (3650 1150) $PN 1
J 0
(3660 1160);
DISPLAY 0.808511 (3660 1160);
FORCEPROP 2 LASTPIN (3500 1150) $PN 2
J 2
(3490 1160);
DISPLAY 0.808511 (3490 1160);
FORCEPROP 2 LAST VALUE DIFF BUS_0.22UF
J 2
(3425 1150);
DISPLAY 0.553191 (3425 1150);
FORCEPROP 1 LAST PIN_NAMES_ROTATE TRUE
J 2
(3575 1150);
DISPLAY 0.489362 (3575 1150);
PAINT GREEN (3575 1150);
DISPLAY INVISIBLE (3575 1150);
FORCEPROP 2 LAST CDS_LIB pure_quanta
J 2
(3575 1150);
DISPLAY INVISIBLE (3575 1150);
FORCEPROP 1 LAST CDS_LMAN_SYM_OUTLINE -25,50,25,-50
J 2
(3575 1150);
DISPLAY 0.468085 (3575 1150);
PAINT GREEN (3575 1150);
DISPLAY INVISIBLE (3575 1150);
FORCEPROP 2 LAST VOLTAGE 6.3V
J 2
(3225 1200);
DISPLAY 0.553191 (3225 1200);
DISPLAY INVISIBLE (3225 1200);
FORCEPROP 1 LAST MATERIAL X6S
J 2
(3584 1229);
DISPLAY 0.574468 (3584 1229);
PAINT GREEN (3584 1229);
DISPLAY INVISIBLE (3584 1229);
FORCEPROP 2 LAST PACK_TYPE C0201
J 2
(3400 1200);
DISPLAY 0.553191 (3400 1200);
DISPLAY INVISIBLE (3400 1200);
FORCEPROP 2 LAST TOLERANCE 20%
J 2
(3500 1200);
DISPLAY 0.553191 (3500 1200);
DISPLAY INVISIBLE (3500 1200);
FORCEPROP 1 LAST PART_NUMBER SP_CH4221MEE01
J 2
(3459 1238);
DISPLAY 0.574468 (3459 1238);
PAINT GREEN (3459 1238);
DISPLAY INVISIBLE (3459 1238);
FORCEPROP 1 LAST LOCATION C827
J 0
(3825 1225);
DISPLAY 1.021277 (3825 1225);
DISPLAY INVISIBLE (3825 1225);
FORCEPROP 1 LAST PATH I343
J 2
(3575 1150);
DISPLAY 0.723404 (3575 1150);
DISPLAY INVISIBLE (3575 1150);
FORCEADD Q_CAP_DIFFBUS..2
R 2
(3575 1200);
FORCEPROP 1 LAST LOCATION C826
J 2
(3809 1217);
DISPLAY 0.723404 (3809 1217);
PAINT GREEN (3809 1217);
FORCEPROP 2 LAST $SEC 1
J 2
(3750 1275);
DISPLAY 0.680851 (3750 1275);
PAINT MONO (3750 1275);
DISPLAY INVISIBLE (3750 1275);
FORCEPROP 2 LAST CDS_SEC 1
J 2
(3750 1275);
DISPLAY 0.680851 (3750 1275);
DISPLAY INVISIBLE (3750 1275);
FORCEPROP 2 LASTPIN (3650 1200) $PN 1
J 0
(3660 1210);
DISPLAY 0.808511 (3660 1210);
FORCEPROP 2 LASTPIN (3500 1200) $PN 2
J 2
(3490 1210);
DISPLAY 0.808511 (3490 1210);
FORCEPROP 2 LAST VALUE DIFF BUS_0.22UF
J 2
(3425 1200);
DISPLAY 0.553191 (3425 1200);
FORCEPROP 1 LAST PIN_NAMES_ROTATE TRUE
J 2
(3575 1200);
DISPLAY 0.489362 (3575 1200);
PAINT GREEN (3575 1200);
DISPLAY INVISIBLE (3575 1200);
FORCEPROP 2 LAST CDS_LIB pure_quanta
J 2
(3575 1200);
DISPLAY INVISIBLE (3575 1200);
FORCEPROP 1 LAST CDS_LMAN_SYM_OUTLINE -25,50,25,-50
J 2
(3575 1200);
DISPLAY 0.468085 (3575 1200);
PAINT GREEN (3575 1200);
DISPLAY INVISIBLE (3575 1200);
FORCEPROP 2 LAST VOLTAGE 6.3V
J 2
(3225 1250);
DISPLAY 0.553191 (3225 1250);
DISPLAY INVISIBLE (3225 1250);
FORCEPROP 1 LAST MATERIAL X6S
J 2
(3584 1279);
DISPLAY 0.574468 (3584 1279);
PAINT GREEN (3584 1279);
DISPLAY INVISIBLE (3584 1279);
FORCEPROP 2 LAST PACK_TYPE C0201
J 2
(3400 1250);
DISPLAY 0.553191 (3400 1250);
DISPLAY INVISIBLE (3400 1250);
FORCEPROP 2 LAST TOLERANCE 20%
J 2
(3500 1250);
DISPLAY 0.553191 (3500 1250);
DISPLAY INVISIBLE (3500 1250);
FORCEPROP 1 LAST PART_NUMBER SP_CH4221MEE01
J 2
(3459 1288);
DISPLAY 0.574468 (3459 1288);
PAINT GREEN (3459 1288);
DISPLAY INVISIBLE (3459 1288);
FORCEPROP 1 LAST LOCATION C826
J 0
(3825 1275);
DISPLAY 1.021277 (3825 1275);
DISPLAY INVISIBLE (3825 1275);
FORCEPROP 1 LAST PATH I344
J 2
(3575 1200);
DISPLAY 0.723404 (3575 1200);
DISPLAY INVISIBLE (3575 1200);
FORCEADD Q_CAP_DIFFBUS..2
R 2
(3575 1600);
FORCEPROP 1 LAST LOCATION C822
J 2
(3809 1617);
DISPLAY 0.723404 (3809 1617);
PAINT GREEN (3809 1617);
FORCEPROP 2 LAST $SEC 1
J 2
(3750 1675);
DISPLAY 0.680851 (3750 1675);
PAINT MONO (3750 1675);
DISPLAY INVISIBLE (3750 1675);
FORCEPROP 2 LAST CDS_SEC 1
J 2
(3750 1675);
DISPLAY 0.680851 (3750 1675);
DISPLAY INVISIBLE (3750 1675);
FORCEPROP 2 LASTPIN (3650 1600) $PN 1
J 0
(3660 1610);
DISPLAY 0.808511 (3660 1610);
FORCEPROP 2 LASTPIN (3500 1600) $PN 2
J 2
(3490 1610);
DISPLAY 0.808511 (3490 1610);
FORCEPROP 2 LAST VALUE DIFF BUS_0.22UF
J 2
(3425 1600);
DISPLAY 0.553191 (3425 1600);
FORCEPROP 1 LAST PIN_NAMES_ROTATE TRUE
J 2
(3575 1600);
DISPLAY 0.489362 (3575 1600);
PAINT GREEN (3575 1600);
DISPLAY INVISIBLE (3575 1600);
FORCEPROP 1 LAST CDS_LMAN_SYM_OUTLINE -25,50,25,-50
J 2
(3575 1600);
DISPLAY 0.468085 (3575 1600);
PAINT GREEN (3575 1600);
DISPLAY INVISIBLE (3575 1600);
FORCEPROP 2 LAST CDS_LIB pure_quanta
J 2
(3575 1600);
DISPLAY INVISIBLE (3575 1600);
FORCEPROP 2 LAST VOLTAGE 6.3V
J 2
(3225 1650);
DISPLAY 0.553191 (3225 1650);
DISPLAY INVISIBLE (3225 1650);
FORCEPROP 1 LAST MATERIAL X6S
J 2
(3584 1679);
DISPLAY 0.574468 (3584 1679);
PAINT GREEN (3584 1679);
DISPLAY INVISIBLE (3584 1679);
FORCEPROP 2 LAST PACK_TYPE C0201
J 2
(3400 1650);
DISPLAY 0.553191 (3400 1650);
DISPLAY INVISIBLE (3400 1650);
FORCEPROP 2 LAST TOLERANCE 20%
J 2
(3500 1650);
DISPLAY 0.553191 (3500 1650);
DISPLAY INVISIBLE (3500 1650);
FORCEPROP 1 LAST PART_NUMBER SP_CH4221MEE01
J 2
(3459 1688);
DISPLAY 0.574468 (3459 1688);
PAINT GREEN (3459 1688);
DISPLAY INVISIBLE (3459 1688);
FORCEPROP 1 LAST LOCATION C822
J 0
(3825 1675);
DISPLAY 1.021277 (3825 1675);
DISPLAY INVISIBLE (3825 1675);
FORCEPROP 1 LAST PATH I345
J 2
(3575 1600);
DISPLAY 0.723404 (3575 1600);
DISPLAY INVISIBLE (3575 1600);
FORCEADD Q_CAP_DIFFBUS..2
R 2
(3575 1550);
FORCEPROP 1 LAST LOCATION C823
J 2
(3809 1567);
DISPLAY 0.723404 (3809 1567);
PAINT GREEN (3809 1567);
FORCEPROP 2 LAST $SEC 1
J 2
(3750 1625);
DISPLAY 0.680851 (3750 1625);
PAINT MONO (3750 1625);
DISPLAY INVISIBLE (3750 1625);
FORCEPROP 2 LAST CDS_SEC 1
J 2
(3750 1625);
DISPLAY 0.680851 (3750 1625);
DISPLAY INVISIBLE (3750 1625);
FORCEPROP 2 LASTPIN (3650 1550) $PN 1
J 0
(3660 1560);
DISPLAY 0.808511 (3660 1560);
FORCEPROP 2 LASTPIN (3500 1550) $PN 2
J 2
(3490 1560);
DISPLAY 0.808511 (3490 1560);
FORCEPROP 2 LAST VALUE DIFF BUS_0.22UF
J 2
(3425 1550);
DISPLAY 0.553191 (3425 1550);
FORCEPROP 1 LAST PIN_NAMES_ROTATE TRUE
J 2
(3575 1550);
DISPLAY 0.489362 (3575 1550);
PAINT GREEN (3575 1550);
DISPLAY INVISIBLE (3575 1550);
FORCEPROP 2 LAST CDS_LIB pure_quanta
J 2
(3575 1550);
DISPLAY INVISIBLE (3575 1550);
FORCEPROP 1 LAST CDS_LMAN_SYM_OUTLINE -25,50,25,-50
J 2
(3575 1550);
DISPLAY 0.468085 (3575 1550);
PAINT GREEN (3575 1550);
DISPLAY INVISIBLE (3575 1550);
FORCEPROP 2 LAST VOLTAGE 6.3V
J 2
(3225 1600);
DISPLAY 0.553191 (3225 1600);
DISPLAY INVISIBLE (3225 1600);
FORCEPROP 1 LAST MATERIAL X6S
J 2
(3584 1629);
DISPLAY 0.574468 (3584 1629);
PAINT GREEN (3584 1629);
DISPLAY INVISIBLE (3584 1629);
FORCEPROP 2 LAST PACK_TYPE C0201
J 2
(3400 1600);
DISPLAY 0.553191 (3400 1600);
DISPLAY INVISIBLE (3400 1600);
FORCEPROP 2 LAST TOLERANCE 20%
J 2
(3500 1600);
DISPLAY 0.553191 (3500 1600);
DISPLAY INVISIBLE (3500 1600);
FORCEPROP 1 LAST PART_NUMBER SP_CH4221MEE01
J 2
(3459 1638);
DISPLAY 0.574468 (3459 1638);
PAINT GREEN (3459 1638);
DISPLAY INVISIBLE (3459 1638);
FORCEPROP 1 LAST LOCATION C823
J 0
(3825 1625);
DISPLAY 1.021277 (3825 1625);
DISPLAY INVISIBLE (3825 1625);
FORCEPROP 1 LAST PATH I346
J 2
(3575 1550);
DISPLAY 0.723404 (3575 1550);
DISPLAY INVISIBLE (3575 1550);
FORCEADD TAP..1
R 2
(2600 2125);
FORCEPROP 3 LASTPIN (2650 2125) SIG_NAME P5E_CPU1_P0_TX_DP<8>
J 0
(2660 2135);
DISPLAY 0.659574 (2660 2135);
PAINT MONO (2660 2135);
DISPLAY INVISIBLE (2660 2135);
FORCEPROP 1 LASTPIN (2650 2125) BN 8
J 2
(2662 2133);
DISPLAY 0.680851 (2662 2133);
PAINT GREEN (2662 2133);
FORCEPROP 2 LAST CDS_LIB standard
J 0
(2600 2125);
DISPLAY INVISIBLE (2600 2125);
FORCEPROP 1 LAST BODY_TYPE PLUMBING
J 2
(2600 2175);
DISPLAY 0.872340 (2600 2175);
PAINT GREEN (2600 2175);
DISPLAY INVISIBLE (2600 2175);
FORCEPROP 1 LAST HDL_TAP TRUE
J 2
(2275 2000);
DISPLAY 0.872340 (2275 2000);
DISPLAY INVISIBLE (2275 2000);
FORCEPROP 1 LAST PATH I347
J 2
(2602 2125);
DISPLAY 0.872340 (2602 2125);
PAINT GREEN (2602 2125);
DISPLAY INVISIBLE (2602 2125);
FORCEADD TAP..1
R 2
(2600 2325);
FORCEPROP 3 LASTPIN (2650 2325) SIG_NAME P5E_CPU1_P0_TX_DP<9>
J 0
(2660 2335);
DISPLAY 0.659574 (2660 2335);
PAINT MONO (2660 2335);
DISPLAY INVISIBLE (2660 2335);
FORCEPROP 1 LASTPIN (2650 2325) BN 9
J 2
(2662 2333);
DISPLAY 0.680851 (2662 2333);
PAINT GREEN (2662 2333);
FORCEPROP 2 LAST CDS_LIB standard
J 0
(2600 2325);
DISPLAY INVISIBLE (2600 2325);
FORCEPROP 1 LAST BODY_TYPE PLUMBING
J 2
(2600 2375);
DISPLAY 0.872340 (2600 2375);
PAINT GREEN (2600 2375);
DISPLAY INVISIBLE (2600 2375);
FORCEPROP 1 LAST HDL_TAP TRUE
J 2
(2275 2200);
DISPLAY 0.872340 (2275 2200);
DISPLAY INVISIBLE (2275 2200);
FORCEPROP 1 LAST PATH I348
J 2
(2602 2325);
DISPLAY 0.872340 (2602 2325);
PAINT GREEN (2602 2325);
DISPLAY INVISIBLE (2602 2325);
FORCEADD TAP..1
R 2
(2600 2525);
FORCEPROP 3 LASTPIN (2650 2525) SIG_NAME P5E_CPU1_P0_TX_DP<10>
J 0
(2660 2535);
DISPLAY 0.659574 (2660 2535);
PAINT MONO (2660 2535);
DISPLAY INVISIBLE (2660 2535);
FORCEPROP 1 LASTPIN (2650 2525) BN 10
J 2
(2662 2533);
DISPLAY 0.680851 (2662 2533);
PAINT GREEN (2662 2533);
FORCEPROP 2 LAST CDS_LIB standard
J 0
(2600 2525);
DISPLAY INVISIBLE (2600 2525);
FORCEPROP 1 LAST BODY_TYPE PLUMBING
J 2
(2600 2575);
DISPLAY 0.872340 (2600 2575);
PAINT GREEN (2600 2575);
DISPLAY INVISIBLE (2600 2575);
FORCEPROP 1 LAST HDL_TAP TRUE
J 2
(2275 2400);
DISPLAY 0.872340 (2275 2400);
DISPLAY INVISIBLE (2275 2400);
FORCEPROP 1 LAST PATH I349
J 2
(2602 2525);
DISPLAY 0.872340 (2602 2525);
PAINT GREEN (2602 2525);
DISPLAY INVISIBLE (2602 2525);
FORCEADD TAP..1
R 2
(2850 2175);
FORCEPROP 3 LASTPIN (2900 2175) SIG_NAME P5E_CPU1_P0_TX_DN<8>
J 0
(2910 2185);
DISPLAY 0.659574 (2910 2185);
PAINT MONO (2910 2185);
DISPLAY INVISIBLE (2910 2185);
FORCEPROP 1 LASTPIN (2900 2175) BN 8
J 2
(2912 2183);
DISPLAY 0.680851 (2912 2183);
PAINT GREEN (2912 2183);
FORCEPROP 2 LAST CDS_LIB standard
J 0
(2850 2175);
DISPLAY INVISIBLE (2850 2175);
FORCEPROP 1 LAST BODY_TYPE PLUMBING
J 2
(2850 2225);
DISPLAY 0.872340 (2850 2225);
PAINT GREEN (2850 2225);
DISPLAY INVISIBLE (2850 2225);
FORCEPROP 1 LAST HDL_TAP TRUE
J 2
(2525 2050);
DISPLAY 0.872340 (2525 2050);
DISPLAY INVISIBLE (2525 2050);
FORCEPROP 1 LAST PATH I350
J 2
(2852 2175);
DISPLAY 0.872340 (2852 2175);
PAINT GREEN (2852 2175);
DISPLAY INVISIBLE (2852 2175);
FORCEADD TAP..1
R 2
(2850 2375);
FORCEPROP 3 LASTPIN (2900 2375) SIG_NAME P5E_CPU1_P0_TX_DN<9>
J 0
(2910 2385);
DISPLAY 0.659574 (2910 2385);
PAINT MONO (2910 2385);
DISPLAY INVISIBLE (2910 2385);
FORCEPROP 1 LASTPIN (2900 2375) BN 9
J 2
(2912 2383);
DISPLAY 0.680851 (2912 2383);
PAINT GREEN (2912 2383);
FORCEPROP 2 LAST CDS_LIB standard
J 0
(2850 2375);
DISPLAY INVISIBLE (2850 2375);
FORCEPROP 1 LAST BODY_TYPE PLUMBING
J 2
(2850 2425);
DISPLAY 0.872340 (2850 2425);
PAINT GREEN (2850 2425);
DISPLAY INVISIBLE (2850 2425);
FORCEPROP 1 LAST HDL_TAP TRUE
J 2
(2525 2250);
DISPLAY 0.872340 (2525 2250);
DISPLAY INVISIBLE (2525 2250);
FORCEPROP 1 LAST PATH I351
J 2
(2852 2375);
DISPLAY 0.872340 (2852 2375);
PAINT GREEN (2852 2375);
DISPLAY INVISIBLE (2852 2375);
FORCEADD TAP..1
R 2
(2600 2725);
FORCEPROP 3 LASTPIN (2650 2725) SIG_NAME P5E_CPU1_P0_TX_DP<11>
J 0
(2660 2735);
DISPLAY 0.659574 (2660 2735);
PAINT MONO (2660 2735);
DISPLAY INVISIBLE (2660 2735);
FORCEPROP 1 LASTPIN (2650 2725) BN 11
J 2
(2662 2733);
DISPLAY 0.680851 (2662 2733);
PAINT GREEN (2662 2733);
FORCEPROP 2 LAST CDS_LIB standard
J 0
(2600 2725);
DISPLAY INVISIBLE (2600 2725);
FORCEPROP 1 LAST BODY_TYPE PLUMBING
J 2
(2600 2775);
DISPLAY 0.872340 (2600 2775);
PAINT GREEN (2600 2775);
DISPLAY INVISIBLE (2600 2775);
FORCEPROP 1 LAST HDL_TAP TRUE
J 2
(2275 2600);
DISPLAY 0.872340 (2275 2600);
DISPLAY INVISIBLE (2275 2600);
FORCEPROP 1 LAST PATH I352
J 2
(2602 2725);
DISPLAY 0.872340 (2602 2725);
PAINT GREEN (2602 2725);
DISPLAY INVISIBLE (2602 2725);
FORCEADD TAP..1
R 2
(2600 2925);
FORCEPROP 3 LASTPIN (2650 2925) SIG_NAME P5E_CPU1_P0_TX_DP<12>
J 0
(2660 2935);
DISPLAY 0.659574 (2660 2935);
PAINT MONO (2660 2935);
DISPLAY INVISIBLE (2660 2935);
FORCEPROP 1 LASTPIN (2650 2925) BN 12
J 2
(2662 2933);
DISPLAY 0.680851 (2662 2933);
PAINT GREEN (2662 2933);
FORCEPROP 2 LAST CDS_LIB standard
J 0
(2600 2925);
DISPLAY INVISIBLE (2600 2925);
FORCEPROP 1 LAST BODY_TYPE PLUMBING
J 2
(2600 2975);
DISPLAY 0.872340 (2600 2975);
PAINT GREEN (2600 2975);
DISPLAY INVISIBLE (2600 2975);
FORCEPROP 1 LAST HDL_TAP TRUE
J 2
(2275 2800);
DISPLAY 0.872340 (2275 2800);
DISPLAY INVISIBLE (2275 2800);
FORCEPROP 1 LAST PATH I353
J 2
(2602 2925);
DISPLAY 0.872340 (2602 2925);
PAINT GREEN (2602 2925);
DISPLAY INVISIBLE (2602 2925);
FORCEADD TAP..1
R 2
(2850 2575);
FORCEPROP 3 LASTPIN (2900 2575) SIG_NAME P5E_CPU1_P0_TX_DN<10>
J 0
(2910 2585);
DISPLAY 0.659574 (2910 2585);
PAINT MONO (2910 2585);
DISPLAY INVISIBLE (2910 2585);
FORCEPROP 1 LASTPIN (2900 2575) BN 10
J 2
(2912 2583);
DISPLAY 0.680851 (2912 2583);
PAINT GREEN (2912 2583);
FORCEPROP 2 LAST CDS_LIB standard
J 0
(2850 2575);
DISPLAY INVISIBLE (2850 2575);
FORCEPROP 1 LAST BODY_TYPE PLUMBING
J 2
(2850 2625);
DISPLAY 0.872340 (2850 2625);
PAINT GREEN (2850 2625);
DISPLAY INVISIBLE (2850 2625);
FORCEPROP 1 LAST HDL_TAP TRUE
J 2
(2525 2450);
DISPLAY 0.872340 (2525 2450);
DISPLAY INVISIBLE (2525 2450);
FORCEPROP 1 LAST PATH I354
J 2
(2852 2575);
DISPLAY 0.872340 (2852 2575);
PAINT GREEN (2852 2575);
DISPLAY INVISIBLE (2852 2575);
FORCEADD TAP..1
R 2
(2850 2775);
FORCEPROP 3 LASTPIN (2900 2775) SIG_NAME P5E_CPU1_P0_TX_DN<11>
J 0
(2910 2785);
DISPLAY 0.659574 (2910 2785);
PAINT MONO (2910 2785);
DISPLAY INVISIBLE (2910 2785);
FORCEPROP 1 LASTPIN (2900 2775) BN 11
J 2
(2912 2783);
DISPLAY 0.680851 (2912 2783);
PAINT GREEN (2912 2783);
FORCEPROP 2 LAST CDS_LIB standard
J 0
(2850 2775);
DISPLAY INVISIBLE (2850 2775);
FORCEPROP 1 LAST BODY_TYPE PLUMBING
J 2
(2850 2825);
DISPLAY 0.872340 (2850 2825);
PAINT GREEN (2850 2825);
DISPLAY INVISIBLE (2850 2825);
FORCEPROP 1 LAST HDL_TAP TRUE
J 2
(2525 2650);
DISPLAY 0.872340 (2525 2650);
DISPLAY INVISIBLE (2525 2650);
FORCEPROP 1 LAST PATH I355
J 2
(2852 2775);
DISPLAY 0.872340 (2852 2775);
PAINT GREEN (2852 2775);
DISPLAY INVISIBLE (2852 2775);
FORCEADD TAP..1
R 2
(2850 2975);
FORCEPROP 3 LASTPIN (2900 2975) SIG_NAME P5E_CPU1_P0_TX_DN<12>
J 0
(2910 2985);
DISPLAY 0.659574 (2910 2985);
PAINT MONO (2910 2985);
DISPLAY INVISIBLE (2910 2985);
FORCEPROP 1 LASTPIN (2900 2975) BN 12
J 2
(2912 2983);
DISPLAY 0.680851 (2912 2983);
PAINT GREEN (2912 2983);
FORCEPROP 2 LAST CDS_LIB standard
J 0
(2850 2975);
DISPLAY INVISIBLE (2850 2975);
FORCEPROP 1 LAST BODY_TYPE PLUMBING
J 2
(2850 3025);
DISPLAY 0.872340 (2850 3025);
PAINT GREEN (2850 3025);
DISPLAY INVISIBLE (2850 3025);
FORCEPROP 1 LAST HDL_TAP TRUE
J 2
(2525 2850);
DISPLAY 0.872340 (2525 2850);
DISPLAY INVISIBLE (2525 2850);
FORCEPROP 1 LAST PATH I356
J 2
(2852 2975);
DISPLAY 0.872340 (2852 2975);
PAINT GREEN (2852 2975);
DISPLAY INVISIBLE (2852 2975);
FORCEADD TAP..1
R 2
(2600 3125);
FORCEPROP 3 LASTPIN (2650 3125) SIG_NAME P5E_CPU1_P0_TX_DP<13>
J 0
(2660 3135);
DISPLAY 0.659574 (2660 3135);
PAINT MONO (2660 3135);
DISPLAY INVISIBLE (2660 3135);
FORCEPROP 1 LASTPIN (2650 3125) BN 13
J 2
(2662 3133);
DISPLAY 0.680851 (2662 3133);
PAINT GREEN (2662 3133);
FORCEPROP 2 LAST CDS_LIB standard
J 0
(2600 3125);
DISPLAY INVISIBLE (2600 3125);
FORCEPROP 1 LAST BODY_TYPE PLUMBING
J 2
(2600 3175);
DISPLAY 0.872340 (2600 3175);
PAINT GREEN (2600 3175);
DISPLAY INVISIBLE (2600 3175);
FORCEPROP 1 LAST HDL_TAP TRUE
J 2
(2275 3000);
DISPLAY 0.872340 (2275 3000);
DISPLAY INVISIBLE (2275 3000);
FORCEPROP 1 LAST PATH I357
J 2
(2602 3125);
DISPLAY 0.872340 (2602 3125);
PAINT GREEN (2602 3125);
DISPLAY INVISIBLE (2602 3125);
FORCEADD TAP..1
R 2
(2600 3325);
FORCEPROP 3 LASTPIN (2650 3325) SIG_NAME P5E_CPU1_P0_TX_DP<14>
J 0
(2660 3335);
DISPLAY 0.659574 (2660 3335);
PAINT MONO (2660 3335);
DISPLAY INVISIBLE (2660 3335);
FORCEPROP 1 LASTPIN (2650 3325) BN 14
J 2
(2662 3333);
DISPLAY 0.680851 (2662 3333);
PAINT GREEN (2662 3333);
FORCEPROP 2 LAST CDS_LIB standard
J 0
(2600 3325);
DISPLAY INVISIBLE (2600 3325);
FORCEPROP 1 LAST BODY_TYPE PLUMBING
J 2
(2600 3375);
DISPLAY 0.872340 (2600 3375);
PAINT GREEN (2600 3375);
DISPLAY INVISIBLE (2600 3375);
FORCEPROP 1 LAST HDL_TAP TRUE
J 2
(2275 3200);
DISPLAY 0.872340 (2275 3200);
DISPLAY INVISIBLE (2275 3200);
FORCEPROP 1 LAST PATH I358
J 2
(2602 3325);
DISPLAY 0.872340 (2602 3325);
PAINT GREEN (2602 3325);
DISPLAY INVISIBLE (2602 3325);
FORCEADD TAP..1
R 2
(2600 3525);
FORCEPROP 3 LASTPIN (2650 3525) SIG_NAME P5E_CPU1_P0_TX_DP<15>
J 0
(2660 3535);
DISPLAY 0.659574 (2660 3535);
PAINT MONO (2660 3535);
DISPLAY INVISIBLE (2660 3535);
FORCEPROP 1 LASTPIN (2650 3525) BN 15
J 2
(2662 3533);
DISPLAY 0.680851 (2662 3533);
PAINT GREEN (2662 3533);
FORCEPROP 2 LAST CDS_LIB standard
J 0
(2600 3525);
DISPLAY INVISIBLE (2600 3525);
FORCEPROP 1 LAST BODY_TYPE PLUMBING
J 2
(2600 3575);
DISPLAY 0.872340 (2600 3575);
PAINT GREEN (2600 3575);
DISPLAY INVISIBLE (2600 3575);
FORCEPROP 1 LAST HDL_TAP TRUE
J 2
(2275 3400);
DISPLAY 0.872340 (2275 3400);
DISPLAY INVISIBLE (2275 3400);
FORCEPROP 1 LAST PATH I359
J 2
(2602 3525);
DISPLAY 0.872340 (2602 3525);
PAINT GREEN (2602 3525);
DISPLAY INVISIBLE (2602 3525);
FORCEADD TAP..1
R 2
(2850 3175);
FORCEPROP 3 LASTPIN (2900 3175) SIG_NAME P5E_CPU1_P0_TX_DN<13>
J 0
(2910 3185);
DISPLAY 0.659574 (2910 3185);
PAINT MONO (2910 3185);
DISPLAY INVISIBLE (2910 3185);
FORCEPROP 1 LASTPIN (2900 3175) BN 13
J 2
(2912 3183);
DISPLAY 0.680851 (2912 3183);
PAINT GREEN (2912 3183);
FORCEPROP 2 LAST CDS_LIB standard
J 0
(2850 3175);
DISPLAY INVISIBLE (2850 3175);
FORCEPROP 1 LAST BODY_TYPE PLUMBING
J 2
(2850 3225);
DISPLAY 0.872340 (2850 3225);
PAINT GREEN (2850 3225);
DISPLAY INVISIBLE (2850 3225);
FORCEPROP 1 LAST HDL_TAP TRUE
J 2
(2525 3050);
DISPLAY 0.872340 (2525 3050);
DISPLAY INVISIBLE (2525 3050);
FORCEPROP 1 LAST PATH I360
J 2
(2852 3175);
DISPLAY 0.872340 (2852 3175);
PAINT GREEN (2852 3175);
DISPLAY INVISIBLE (2852 3175);
FORCEADD TAP..1
R 2
(2850 3375);
FORCEPROP 3 LASTPIN (2900 3375) SIG_NAME P5E_CPU1_P0_TX_DN<14>
J 0
(2910 3385);
DISPLAY 0.659574 (2910 3385);
PAINT MONO (2910 3385);
DISPLAY INVISIBLE (2910 3385);
FORCEPROP 1 LASTPIN (2900 3375) BN 14
J 2
(2912 3383);
DISPLAY 0.680851 (2912 3383);
PAINT GREEN (2912 3383);
FORCEPROP 2 LAST CDS_LIB standard
J 0
(2850 3375);
DISPLAY INVISIBLE (2850 3375);
FORCEPROP 1 LAST BODY_TYPE PLUMBING
J 2
(2850 3425);
DISPLAY 0.872340 (2850 3425);
PAINT GREEN (2850 3425);
DISPLAY INVISIBLE (2850 3425);
FORCEPROP 1 LAST HDL_TAP TRUE
J 2
(2525 3250);
DISPLAY 0.872340 (2525 3250);
DISPLAY INVISIBLE (2525 3250);
FORCEPROP 1 LAST PATH I361
J 2
(2852 3375);
DISPLAY 0.872340 (2852 3375);
PAINT GREEN (2852 3375);
DISPLAY INVISIBLE (2852 3375);
FORCEADD TAP..1
R 2
(2850 3575);
FORCEPROP 3 LASTPIN (2900 3575) SIG_NAME P5E_CPU1_P0_TX_DN<15>
J 0
(2910 3585);
DISPLAY 0.659574 (2910 3585);
PAINT MONO (2910 3585);
DISPLAY INVISIBLE (2910 3585);
FORCEPROP 1 LASTPIN (2900 3575) BN 15
J 2
(2912 3583);
DISPLAY 0.680851 (2912 3583);
PAINT GREEN (2912 3583);
FORCEPROP 2 LAST CDS_LIB standard
J 0
(2850 3575);
DISPLAY INVISIBLE (2850 3575);
FORCEPROP 1 LAST BODY_TYPE PLUMBING
J 2
(2850 3625);
DISPLAY 0.872340 (2850 3625);
PAINT GREEN (2850 3625);
DISPLAY INVISIBLE (2850 3625);
FORCEPROP 1 LAST HDL_TAP TRUE
J 2
(2525 3450);
DISPLAY 0.872340 (2525 3450);
DISPLAY INVISIBLE (2525 3450);
FORCEPROP 1 LAST PATH I362
J 2
(2852 3575);
DISPLAY 0.872340 (2852 3575);
PAINT GREEN (2852 3575);
DISPLAY INVISIBLE (2852 3575);
FORCEADD Q_CAP_DIFFBUS..2
R 2
(3575 2175);
FORCEPROP 1 LAST LOCATION C820
J 2
(3809 2192);
DISPLAY 0.723404 (3809 2192);
PAINT GREEN (3809 2192);
FORCEPROP 2 LAST $SEC 1
J 2
(3750 2250);
DISPLAY 0.680851 (3750 2250);
PAINT MONO (3750 2250);
DISPLAY INVISIBLE (3750 2250);
FORCEPROP 2 LAST CDS_SEC 1
J 2
(3750 2250);
DISPLAY 0.680851 (3750 2250);
DISPLAY INVISIBLE (3750 2250);
FORCEPROP 2 LASTPIN (3650 2175) $PN 1
J 0
(3660 2185);
DISPLAY 0.808511 (3660 2185);
FORCEPROP 2 LASTPIN (3500 2175) $PN 2
J 2
(3490 2185);
DISPLAY 0.808511 (3490 2185);
FORCEPROP 2 LAST VALUE DIFF BUS_0.22UF
J 2
(3425 2175);
DISPLAY 0.553191 (3425 2175);
FORCEPROP 1 LAST CDS_LMAN_SYM_OUTLINE -25,50,25,-50
J 2
(3575 2175);
DISPLAY 0.468085 (3575 2175);
PAINT GREEN (3575 2175);
DISPLAY INVISIBLE (3575 2175);
FORCEPROP 2 LAST CDS_LIB pure_quanta
J 2
(3575 2175);
DISPLAY INVISIBLE (3575 2175);
FORCEPROP 1 LAST PIN_NAMES_ROTATE TRUE
J 2
(3575 2175);
DISPLAY 0.489362 (3575 2175);
PAINT GREEN (3575 2175);
DISPLAY INVISIBLE (3575 2175);
FORCEPROP 2 LAST VOLTAGE 6.3V
J 2
(3225 2225);
DISPLAY 0.553191 (3225 2225);
DISPLAY INVISIBLE (3225 2225);
FORCEPROP 1 LAST MATERIAL X6S
J 2
(3584 2254);
DISPLAY 0.574468 (3584 2254);
PAINT GREEN (3584 2254);
DISPLAY INVISIBLE (3584 2254);
FORCEPROP 2 LAST PACK_TYPE C0201
J 2
(3400 2225);
DISPLAY 0.553191 (3400 2225);
DISPLAY INVISIBLE (3400 2225);
FORCEPROP 2 LAST TOLERANCE 20%
J 2
(3500 2225);
DISPLAY 0.553191 (3500 2225);
DISPLAY INVISIBLE (3500 2225);
FORCEPROP 1 LAST PART_NUMBER SP_CH4221MEE01
J 2
(3459 2263);
DISPLAY 0.574468 (3459 2263);
PAINT GREEN (3459 2263);
DISPLAY INVISIBLE (3459 2263);
FORCEPROP 1 LAST LOCATION C820
J 0
(3825 2250);
DISPLAY 1.021277 (3825 2250);
DISPLAY INVISIBLE (3825 2250);
FORCEPROP 1 LAST PATH I363
J 2
(3575 2175);
DISPLAY 0.723404 (3575 2175);
DISPLAY INVISIBLE (3575 2175);
FORCEADD Q_CAP_DIFFBUS..2
R 2
(3575 2125);
FORCEPROP 1 LAST LOCATION C821
J 2
(3809 2142);
DISPLAY 0.723404 (3809 2142);
PAINT GREEN (3809 2142);
FORCEPROP 2 LAST $SEC 1
J 2
(3750 2200);
DISPLAY 0.680851 (3750 2200);
PAINT MONO (3750 2200);
DISPLAY INVISIBLE (3750 2200);
FORCEPROP 2 LAST CDS_SEC 1
J 2
(3750 2200);
DISPLAY 0.680851 (3750 2200);
DISPLAY INVISIBLE (3750 2200);
FORCEPROP 2 LASTPIN (3650 2125) $PN 1
J 0
(3660 2135);
DISPLAY 0.808511 (3660 2135);
FORCEPROP 2 LASTPIN (3500 2125) $PN 2
J 2
(3490 2135);
DISPLAY 0.808511 (3490 2135);
FORCEPROP 2 LAST VALUE DIFF BUS_0.22UF
J 2
(3425 2125);
DISPLAY 0.553191 (3425 2125);
FORCEPROP 1 LAST CDS_LMAN_SYM_OUTLINE -25,50,25,-50
J 2
(3575 2125);
DISPLAY 0.468085 (3575 2125);
PAINT GREEN (3575 2125);
DISPLAY INVISIBLE (3575 2125);
FORCEPROP 2 LAST CDS_LIB pure_quanta
J 2
(3575 2125);
DISPLAY INVISIBLE (3575 2125);
FORCEPROP 1 LAST PIN_NAMES_ROTATE TRUE
J 2
(3575 2125);
DISPLAY 0.489362 (3575 2125);
PAINT GREEN (3575 2125);
DISPLAY INVISIBLE (3575 2125);
FORCEPROP 2 LAST VOLTAGE 6.3V
J 2
(3225 2175);
DISPLAY 0.553191 (3225 2175);
DISPLAY INVISIBLE (3225 2175);
FORCEPROP 1 LAST MATERIAL X6S
J 2
(3584 2204);
DISPLAY 0.574468 (3584 2204);
PAINT GREEN (3584 2204);
DISPLAY INVISIBLE (3584 2204);
FORCEPROP 2 LAST PACK_TYPE C0201
J 2
(3400 2175);
DISPLAY 0.553191 (3400 2175);
DISPLAY INVISIBLE (3400 2175);
FORCEPROP 2 LAST TOLERANCE 20%
J 2
(3500 2175);
DISPLAY 0.553191 (3500 2175);
DISPLAY INVISIBLE (3500 2175);
FORCEPROP 1 LAST PART_NUMBER SP_CH4221MEE01
J 2
(3459 2213);
DISPLAY 0.574468 (3459 2213);
PAINT GREEN (3459 2213);
DISPLAY INVISIBLE (3459 2213);
FORCEPROP 1 LAST LOCATION C821
J 0
(3825 2200);
DISPLAY 1.021277 (3825 2200);
DISPLAY INVISIBLE (3825 2200);
FORCEPROP 1 LAST PATH I364
J 2
(3575 2125);
DISPLAY 0.723404 (3575 2125);
DISPLAY INVISIBLE (3575 2125);
FORCEADD Q_CAP_DIFFBUS..2
R 2
(3575 2375);
FORCEPROP 1 LAST LOCATION C818
J 2
(3809 2392);
DISPLAY 0.723404 (3809 2392);
PAINT GREEN (3809 2392);
FORCEPROP 2 LAST $SEC 1
J 2
(3750 2450);
DISPLAY 0.680851 (3750 2450);
PAINT MONO (3750 2450);
DISPLAY INVISIBLE (3750 2450);
FORCEPROP 2 LAST CDS_SEC 1
J 2
(3750 2450);
DISPLAY 0.680851 (3750 2450);
DISPLAY INVISIBLE (3750 2450);
FORCEPROP 2 LASTPIN (3650 2375) $PN 1
J 0
(3660 2385);
DISPLAY 0.808511 (3660 2385);
FORCEPROP 2 LASTPIN (3500 2375) $PN 2
J 2
(3490 2385);
DISPLAY 0.808511 (3490 2385);
FORCEPROP 2 LAST VALUE DIFF BUS_0.22UF
J 2
(3425 2375);
DISPLAY 0.553191 (3425 2375);
FORCEPROP 2 LAST CDS_LIB pure_quanta
J 2
(3575 2375);
DISPLAY INVISIBLE (3575 2375);
FORCEPROP 1 LAST CDS_LMAN_SYM_OUTLINE -25,50,25,-50
J 2
(3575 2375);
DISPLAY 0.468085 (3575 2375);
PAINT GREEN (3575 2375);
DISPLAY INVISIBLE (3575 2375);
FORCEPROP 1 LAST PIN_NAMES_ROTATE TRUE
J 2
(3575 2375);
DISPLAY 0.489362 (3575 2375);
PAINT GREEN (3575 2375);
DISPLAY INVISIBLE (3575 2375);
FORCEPROP 2 LAST VOLTAGE 6.3V
J 2
(3225 2425);
DISPLAY 0.553191 (3225 2425);
DISPLAY INVISIBLE (3225 2425);
FORCEPROP 1 LAST MATERIAL X6S
J 2
(3584 2454);
DISPLAY 0.574468 (3584 2454);
PAINT GREEN (3584 2454);
DISPLAY INVISIBLE (3584 2454);
FORCEPROP 2 LAST PACK_TYPE C0201
J 2
(3400 2425);
DISPLAY 0.553191 (3400 2425);
DISPLAY INVISIBLE (3400 2425);
FORCEPROP 2 LAST TOLERANCE 20%
J 2
(3500 2425);
DISPLAY 0.553191 (3500 2425);
DISPLAY INVISIBLE (3500 2425);
FORCEPROP 1 LAST PART_NUMBER SP_CH4221MEE01
J 2
(3459 2463);
DISPLAY 0.574468 (3459 2463);
PAINT GREEN (3459 2463);
DISPLAY INVISIBLE (3459 2463);
FORCEPROP 1 LAST LOCATION C818
J 0
(3825 2450);
DISPLAY 1.021277 (3825 2450);
DISPLAY INVISIBLE (3825 2450);
FORCEPROP 1 LAST PATH I365
J 2
(3575 2375);
DISPLAY 0.723404 (3575 2375);
DISPLAY INVISIBLE (3575 2375);
FORCEADD Q_CAP_DIFFBUS..2
R 2
(3575 2325);
FORCEPROP 1 LAST LOCATION C819
J 2
(3809 2342);
DISPLAY 0.723404 (3809 2342);
PAINT GREEN (3809 2342);
FORCEPROP 2 LAST $SEC 1
J 2
(3750 2400);
DISPLAY 0.680851 (3750 2400);
PAINT MONO (3750 2400);
DISPLAY INVISIBLE (3750 2400);
FORCEPROP 2 LAST CDS_SEC 1
J 2
(3750 2400);
DISPLAY 0.680851 (3750 2400);
DISPLAY INVISIBLE (3750 2400);
FORCEPROP 2 LASTPIN (3650 2325) $PN 1
J 0
(3660 2335);
DISPLAY 0.808511 (3660 2335);
FORCEPROP 2 LASTPIN (3500 2325) $PN 2
J 2
(3490 2335);
DISPLAY 0.808511 (3490 2335);
FORCEPROP 2 LAST VALUE DIFF BUS_0.22UF
J 2
(3425 2325);
DISPLAY 0.553191 (3425 2325);
FORCEPROP 1 LAST CDS_LMAN_SYM_OUTLINE -25,50,25,-50
J 2
(3575 2325);
DISPLAY 0.468085 (3575 2325);
PAINT GREEN (3575 2325);
DISPLAY INVISIBLE (3575 2325);
FORCEPROP 2 LAST CDS_LIB pure_quanta
J 2
(3575 2325);
DISPLAY INVISIBLE (3575 2325);
FORCEPROP 1 LAST PIN_NAMES_ROTATE TRUE
J 2
(3575 2325);
DISPLAY 0.489362 (3575 2325);
PAINT GREEN (3575 2325);
DISPLAY INVISIBLE (3575 2325);
FORCEPROP 2 LAST VOLTAGE 6.3V
J 2
(3225 2375);
DISPLAY 0.553191 (3225 2375);
DISPLAY INVISIBLE (3225 2375);
FORCEPROP 1 LAST MATERIAL X6S
J 2
(3584 2404);
DISPLAY 0.574468 (3584 2404);
PAINT GREEN (3584 2404);
DISPLAY INVISIBLE (3584 2404);
FORCEPROP 2 LAST PACK_TYPE C0201
J 2
(3400 2375);
DISPLAY 0.553191 (3400 2375);
DISPLAY INVISIBLE (3400 2375);
FORCEPROP 2 LAST TOLERANCE 20%
J 2
(3500 2375);
DISPLAY 0.553191 (3500 2375);
DISPLAY INVISIBLE (3500 2375);
FORCEPROP 1 LAST PART_NUMBER SP_CH4221MEE01
J 2
(3459 2413);
DISPLAY 0.574468 (3459 2413);
PAINT GREEN (3459 2413);
DISPLAY INVISIBLE (3459 2413);
FORCEPROP 1 LAST LOCATION C819
J 0
(3825 2400);
DISPLAY 1.021277 (3825 2400);
DISPLAY INVISIBLE (3825 2400);
FORCEPROP 1 LAST PATH I366
J 2
(3575 2325);
DISPLAY 0.723404 (3575 2325);
DISPLAY INVISIBLE (3575 2325);
FORCEADD Q_CAP_DIFFBUS..2
R 2
(3575 2525);
FORCEPROP 1 LAST LOCATION C817
J 2
(3809 2542);
DISPLAY 0.723404 (3809 2542);
PAINT GREEN (3809 2542);
FORCEPROP 2 LAST $SEC 1
J 2
(3750 2600);
DISPLAY 0.680851 (3750 2600);
PAINT MONO (3750 2600);
DISPLAY INVISIBLE (3750 2600);
FORCEPROP 2 LAST CDS_SEC 1
J 2
(3750 2600);
DISPLAY 0.680851 (3750 2600);
DISPLAY INVISIBLE (3750 2600);
FORCEPROP 2 LASTPIN (3650 2525) $PN 1
J 0
(3660 2535);
DISPLAY 0.808511 (3660 2535);
FORCEPROP 2 LASTPIN (3500 2525) $PN 2
J 2
(3490 2535);
DISPLAY 0.808511 (3490 2535);
FORCEPROP 2 LAST VALUE DIFF BUS_0.22UF
J 2
(3425 2525);
DISPLAY 0.553191 (3425 2525);
FORCEPROP 1 LAST CDS_LMAN_SYM_OUTLINE -25,50,25,-50
J 2
(3575 2525);
DISPLAY 0.468085 (3575 2525);
PAINT GREEN (3575 2525);
DISPLAY INVISIBLE (3575 2525);
FORCEPROP 2 LAST CDS_LIB pure_quanta
J 2
(3575 2525);
DISPLAY INVISIBLE (3575 2525);
FORCEPROP 1 LAST PIN_NAMES_ROTATE TRUE
J 2
(3575 2525);
DISPLAY 0.489362 (3575 2525);
PAINT GREEN (3575 2525);
DISPLAY INVISIBLE (3575 2525);
FORCEPROP 2 LAST VOLTAGE 6.3V
J 2
(3225 2575);
DISPLAY 0.553191 (3225 2575);
DISPLAY INVISIBLE (3225 2575);
FORCEPROP 1 LAST MATERIAL X6S
J 2
(3584 2604);
DISPLAY 0.574468 (3584 2604);
PAINT GREEN (3584 2604);
DISPLAY INVISIBLE (3584 2604);
FORCEPROP 2 LAST PACK_TYPE C0201
J 2
(3400 2575);
DISPLAY 0.553191 (3400 2575);
DISPLAY INVISIBLE (3400 2575);
FORCEPROP 2 LAST TOLERANCE 20%
J 2
(3500 2575);
DISPLAY 0.553191 (3500 2575);
DISPLAY INVISIBLE (3500 2575);
FORCEPROP 1 LAST PART_NUMBER SP_CH4221MEE01
J 2
(3459 2613);
DISPLAY 0.574468 (3459 2613);
PAINT GREEN (3459 2613);
DISPLAY INVISIBLE (3459 2613);
FORCEPROP 1 LAST LOCATION C817
J 0
(3825 2600);
DISPLAY 1.021277 (3825 2600);
DISPLAY INVISIBLE (3825 2600);
FORCEPROP 1 LAST PATH I367
J 2
(3575 2525);
DISPLAY 0.723404 (3575 2525);
DISPLAY INVISIBLE (3575 2525);
FORCEADD Q_CAP_DIFFBUS..2
R 2
(3575 2575);
FORCEPROP 1 LAST LOCATION C816
J 2
(3809 2592);
DISPLAY 0.723404 (3809 2592);
PAINT GREEN (3809 2592);
FORCEPROP 2 LAST $SEC 1
J 2
(3750 2650);
DISPLAY 0.680851 (3750 2650);
PAINT MONO (3750 2650);
DISPLAY INVISIBLE (3750 2650);
FORCEPROP 2 LAST CDS_SEC 1
J 2
(3750 2650);
DISPLAY 0.680851 (3750 2650);
DISPLAY INVISIBLE (3750 2650);
FORCEPROP 2 LASTPIN (3650 2575) $PN 1
J 0
(3660 2585);
DISPLAY 0.808511 (3660 2585);
FORCEPROP 2 LASTPIN (3500 2575) $PN 2
J 2
(3490 2585);
DISPLAY 0.808511 (3490 2585);
FORCEPROP 2 LAST VALUE DIFF BUS_0.22UF
J 2
(3425 2575);
DISPLAY 0.553191 (3425 2575);
FORCEPROP 1 LAST CDS_LMAN_SYM_OUTLINE -25,50,25,-50
J 2
(3575 2575);
DISPLAY 0.468085 (3575 2575);
PAINT GREEN (3575 2575);
DISPLAY INVISIBLE (3575 2575);
FORCEPROP 2 LAST CDS_LIB pure_quanta
J 2
(3575 2575);
DISPLAY INVISIBLE (3575 2575);
FORCEPROP 1 LAST PIN_NAMES_ROTATE TRUE
J 2
(3575 2575);
DISPLAY 0.489362 (3575 2575);
PAINT GREEN (3575 2575);
DISPLAY INVISIBLE (3575 2575);
FORCEPROP 2 LAST VOLTAGE 6.3V
J 2
(3225 2625);
DISPLAY 0.553191 (3225 2625);
DISPLAY INVISIBLE (3225 2625);
FORCEPROP 1 LAST MATERIAL X6S
J 2
(3584 2654);
DISPLAY 0.574468 (3584 2654);
PAINT GREEN (3584 2654);
DISPLAY INVISIBLE (3584 2654);
FORCEPROP 2 LAST PACK_TYPE C0201
J 2
(3400 2625);
DISPLAY 0.553191 (3400 2625);
DISPLAY INVISIBLE (3400 2625);
FORCEPROP 2 LAST TOLERANCE 20%
J 2
(3500 2625);
DISPLAY 0.553191 (3500 2625);
DISPLAY INVISIBLE (3500 2625);
FORCEPROP 1 LAST PART_NUMBER SP_CH4221MEE01
J 2
(3459 2663);
DISPLAY 0.574468 (3459 2663);
PAINT GREEN (3459 2663);
DISPLAY INVISIBLE (3459 2663);
FORCEPROP 1 LAST LOCATION C816
J 0
(3825 2650);
DISPLAY 1.021277 (3825 2650);
DISPLAY INVISIBLE (3825 2650);
FORCEPROP 1 LAST PATH I368
J 2
(3575 2575);
DISPLAY 0.723404 (3575 2575);
DISPLAY INVISIBLE (3575 2575);
FORCEADD Q_CAP_DIFFBUS..2
R 2
(3575 2725);
FORCEPROP 1 LAST LOCATION C815
J 2
(3809 2742);
DISPLAY 0.723404 (3809 2742);
PAINT GREEN (3809 2742);
FORCEPROP 2 LAST $SEC 1
J 2
(3750 2800);
DISPLAY 0.680851 (3750 2800);
PAINT MONO (3750 2800);
DISPLAY INVISIBLE (3750 2800);
FORCEPROP 2 LAST CDS_SEC 1
J 2
(3750 2800);
DISPLAY 0.680851 (3750 2800);
DISPLAY INVISIBLE (3750 2800);
FORCEPROP 2 LASTPIN (3650 2725) $PN 1
J 0
(3660 2735);
DISPLAY 0.808511 (3660 2735);
FORCEPROP 2 LASTPIN (3500 2725) $PN 2
J 2
(3490 2735);
DISPLAY 0.808511 (3490 2735);
FORCEPROP 2 LAST VALUE DIFF BUS_0.22UF
J 2
(3425 2725);
DISPLAY 0.553191 (3425 2725);
FORCEPROP 2 LAST CDS_LIB pure_quanta
J 2
(3575 2725);
DISPLAY INVISIBLE (3575 2725);
FORCEPROP 1 LAST CDS_LMAN_SYM_OUTLINE -25,50,25,-50
J 2
(3575 2725);
DISPLAY 0.468085 (3575 2725);
PAINT GREEN (3575 2725);
DISPLAY INVISIBLE (3575 2725);
FORCEPROP 1 LAST PIN_NAMES_ROTATE TRUE
J 2
(3575 2725);
DISPLAY 0.489362 (3575 2725);
PAINT GREEN (3575 2725);
DISPLAY INVISIBLE (3575 2725);
FORCEPROP 2 LAST VOLTAGE 6.3V
J 2
(3225 2775);
DISPLAY 0.553191 (3225 2775);
DISPLAY INVISIBLE (3225 2775);
FORCEPROP 1 LAST MATERIAL X6S
J 2
(3584 2804);
DISPLAY 0.574468 (3584 2804);
PAINT GREEN (3584 2804);
DISPLAY INVISIBLE (3584 2804);
FORCEPROP 2 LAST PACK_TYPE C0201
J 2
(3400 2775);
DISPLAY 0.553191 (3400 2775);
DISPLAY INVISIBLE (3400 2775);
FORCEPROP 2 LAST TOLERANCE 20%
J 2
(3500 2775);
DISPLAY 0.553191 (3500 2775);
DISPLAY INVISIBLE (3500 2775);
FORCEPROP 1 LAST PART_NUMBER SP_CH4221MEE01
J 2
(3459 2813);
DISPLAY 0.574468 (3459 2813);
PAINT GREEN (3459 2813);
DISPLAY INVISIBLE (3459 2813);
FORCEPROP 1 LAST LOCATION C815
J 0
(3825 2800);
DISPLAY 1.021277 (3825 2800);
DISPLAY INVISIBLE (3825 2800);
FORCEPROP 1 LAST PATH I369
J 2
(3575 2725);
DISPLAY 0.723404 (3575 2725);
DISPLAY INVISIBLE (3575 2725);
FORCEADD Q_CAP_DIFFBUS..2
R 2
(3575 2775);
FORCEPROP 1 LAST LOCATION C814
J 2
(3809 2792);
DISPLAY 0.723404 (3809 2792);
PAINT GREEN (3809 2792);
FORCEPROP 2 LAST $SEC 1
J 2
(3750 2850);
DISPLAY 0.680851 (3750 2850);
PAINT MONO (3750 2850);
DISPLAY INVISIBLE (3750 2850);
FORCEPROP 2 LAST CDS_SEC 1
J 2
(3750 2850);
DISPLAY 0.680851 (3750 2850);
DISPLAY INVISIBLE (3750 2850);
FORCEPROP 2 LASTPIN (3650 2775) $PN 1
J 0
(3660 2785);
DISPLAY 0.808511 (3660 2785);
FORCEPROP 2 LASTPIN (3500 2775) $PN 2
J 2
(3490 2785);
DISPLAY 0.808511 (3490 2785);
FORCEPROP 2 LAST VALUE DIFF BUS_0.22UF
J 2
(3425 2775);
DISPLAY 0.553191 (3425 2775);
FORCEPROP 2 LAST CDS_LIB pure_quanta
J 2
(3575 2775);
DISPLAY INVISIBLE (3575 2775);
FORCEPROP 1 LAST CDS_LMAN_SYM_OUTLINE -25,50,25,-50
J 2
(3575 2775);
DISPLAY 0.468085 (3575 2775);
PAINT GREEN (3575 2775);
DISPLAY INVISIBLE (3575 2775);
FORCEPROP 1 LAST PIN_NAMES_ROTATE TRUE
J 2
(3575 2775);
DISPLAY 0.489362 (3575 2775);
PAINT GREEN (3575 2775);
DISPLAY INVISIBLE (3575 2775);
FORCEPROP 2 LAST VOLTAGE 6.3V
J 2
(3225 2825);
DISPLAY 0.553191 (3225 2825);
DISPLAY INVISIBLE (3225 2825);
FORCEPROP 1 LAST MATERIAL X6S
J 2
(3584 2854);
DISPLAY 0.574468 (3584 2854);
PAINT GREEN (3584 2854);
DISPLAY INVISIBLE (3584 2854);
FORCEPROP 2 LAST PACK_TYPE C0201
J 2
(3400 2825);
DISPLAY 0.553191 (3400 2825);
DISPLAY INVISIBLE (3400 2825);
FORCEPROP 2 LAST TOLERANCE 20%
J 2
(3500 2825);
DISPLAY 0.553191 (3500 2825);
DISPLAY INVISIBLE (3500 2825);
FORCEPROP 1 LAST PART_NUMBER SP_CH4221MEE01
J 2
(3459 2863);
DISPLAY 0.574468 (3459 2863);
PAINT GREEN (3459 2863);
DISPLAY INVISIBLE (3459 2863);
FORCEPROP 1 LAST LOCATION C814
J 0
(3825 2850);
DISPLAY 1.021277 (3825 2850);
DISPLAY INVISIBLE (3825 2850);
FORCEPROP 1 LAST PATH I370
J 2
(3575 2775);
DISPLAY 0.723404 (3575 2775);
DISPLAY INVISIBLE (3575 2775);
FORCEADD Q_CAP_DIFFBUS..2
R 2
(3575 2975);
FORCEPROP 1 LAST LOCATION C812
J 2
(3809 2992);
DISPLAY 0.723404 (3809 2992);
PAINT GREEN (3809 2992);
FORCEPROP 2 LAST $SEC 1
J 2
(3750 3050);
DISPLAY 0.680851 (3750 3050);
PAINT MONO (3750 3050);
DISPLAY INVISIBLE (3750 3050);
FORCEPROP 2 LAST CDS_SEC 1
J 2
(3750 3050);
DISPLAY 0.680851 (3750 3050);
DISPLAY INVISIBLE (3750 3050);
FORCEPROP 2 LASTPIN (3650 2975) $PN 1
J 0
(3660 2985);
DISPLAY 0.808511 (3660 2985);
FORCEPROP 2 LASTPIN (3500 2975) $PN 2
J 2
(3490 2985);
DISPLAY 0.808511 (3490 2985);
FORCEPROP 2 LAST VALUE DIFF BUS_0.22UF
J 2
(3425 2975);
DISPLAY 0.553191 (3425 2975);
FORCEPROP 1 LAST CDS_LMAN_SYM_OUTLINE -25,50,25,-50
J 2
(3575 2975);
DISPLAY 0.468085 (3575 2975);
PAINT GREEN (3575 2975);
DISPLAY INVISIBLE (3575 2975);
FORCEPROP 2 LAST CDS_LIB pure_quanta
J 2
(3575 2975);
DISPLAY INVISIBLE (3575 2975);
FORCEPROP 1 LAST PIN_NAMES_ROTATE TRUE
J 2
(3575 2975);
DISPLAY 0.489362 (3575 2975);
PAINT GREEN (3575 2975);
DISPLAY INVISIBLE (3575 2975);
FORCEPROP 2 LAST VOLTAGE 6.3V
J 2
(3225 3025);
DISPLAY 0.553191 (3225 3025);
DISPLAY INVISIBLE (3225 3025);
FORCEPROP 1 LAST MATERIAL X6S
J 2
(3584 3054);
DISPLAY 0.574468 (3584 3054);
PAINT GREEN (3584 3054);
DISPLAY INVISIBLE (3584 3054);
FORCEPROP 2 LAST PACK_TYPE C0201
J 2
(3400 3025);
DISPLAY 0.553191 (3400 3025);
DISPLAY INVISIBLE (3400 3025);
FORCEPROP 2 LAST TOLERANCE 20%
J 2
(3500 3025);
DISPLAY 0.553191 (3500 3025);
DISPLAY INVISIBLE (3500 3025);
FORCEPROP 1 LAST PART_NUMBER SP_CH4221MEE01
J 2
(3459 3063);
DISPLAY 0.574468 (3459 3063);
PAINT GREEN (3459 3063);
DISPLAY INVISIBLE (3459 3063);
FORCEPROP 1 LAST LOCATION C812
J 0
(3825 3050);
DISPLAY 1.021277 (3825 3050);
DISPLAY INVISIBLE (3825 3050);
FORCEPROP 1 LAST PATH I371
J 2
(3575 2975);
DISPLAY 0.723404 (3575 2975);
DISPLAY INVISIBLE (3575 2975);
FORCEADD Q_CAP_DIFFBUS..2
R 2
(3575 2925);
FORCEPROP 1 LAST LOCATION C813
J 2
(3809 2942);
DISPLAY 0.723404 (3809 2942);
PAINT GREEN (3809 2942);
FORCEPROP 2 LAST $SEC 1
J 2
(3750 3000);
DISPLAY 0.680851 (3750 3000);
PAINT MONO (3750 3000);
DISPLAY INVISIBLE (3750 3000);
FORCEPROP 2 LAST CDS_SEC 1
J 2
(3750 3000);
DISPLAY 0.680851 (3750 3000);
DISPLAY INVISIBLE (3750 3000);
FORCEPROP 2 LASTPIN (3650 2925) $PN 1
J 0
(3660 2935);
DISPLAY 0.808511 (3660 2935);
FORCEPROP 2 LASTPIN (3500 2925) $PN 2
J 2
(3490 2935);
DISPLAY 0.808511 (3490 2935);
FORCEPROP 2 LAST VALUE DIFF BUS_0.22UF
J 2
(3425 2925);
DISPLAY 0.553191 (3425 2925);
FORCEPROP 1 LAST CDS_LMAN_SYM_OUTLINE -25,50,25,-50
J 2
(3575 2925);
DISPLAY 0.468085 (3575 2925);
PAINT GREEN (3575 2925);
DISPLAY INVISIBLE (3575 2925);
FORCEPROP 2 LAST CDS_LIB pure_quanta
J 2
(3575 2925);
DISPLAY INVISIBLE (3575 2925);
FORCEPROP 1 LAST PIN_NAMES_ROTATE TRUE
J 2
(3575 2925);
DISPLAY 0.489362 (3575 2925);
PAINT GREEN (3575 2925);
DISPLAY INVISIBLE (3575 2925);
FORCEPROP 2 LAST VOLTAGE 6.3V
J 2
(3225 2975);
DISPLAY 0.553191 (3225 2975);
DISPLAY INVISIBLE (3225 2975);
FORCEPROP 1 LAST MATERIAL X6S
J 2
(3584 3004);
DISPLAY 0.574468 (3584 3004);
PAINT GREEN (3584 3004);
DISPLAY INVISIBLE (3584 3004);
FORCEPROP 2 LAST PACK_TYPE C0201
J 2
(3400 2975);
DISPLAY 0.553191 (3400 2975);
DISPLAY INVISIBLE (3400 2975);
FORCEPROP 2 LAST TOLERANCE 20%
J 2
(3500 2975);
DISPLAY 0.553191 (3500 2975);
DISPLAY INVISIBLE (3500 2975);
FORCEPROP 1 LAST PART_NUMBER SP_CH4221MEE01
J 2
(3459 3013);
DISPLAY 0.574468 (3459 3013);
PAINT GREEN (3459 3013);
DISPLAY INVISIBLE (3459 3013);
FORCEPROP 1 LAST LOCATION C813
J 0
(3825 3000);
DISPLAY 1.021277 (3825 3000);
DISPLAY INVISIBLE (3825 3000);
FORCEPROP 1 LAST PATH I372
J 2
(3575 2925);
DISPLAY 0.723404 (3575 2925);
DISPLAY INVISIBLE (3575 2925);
FORCEADD Q_CAP_DIFFBUS..2
R 2
(3575 3125);
FORCEPROP 1 LAST LOCATION C811
J 2
(3809 3142);
DISPLAY 0.723404 (3809 3142);
PAINT GREEN (3809 3142);
FORCEPROP 2 LAST $SEC 1
J 2
(3750 3200);
DISPLAY 0.680851 (3750 3200);
PAINT MONO (3750 3200);
DISPLAY INVISIBLE (3750 3200);
FORCEPROP 2 LAST CDS_SEC 1
J 2
(3750 3200);
DISPLAY 0.680851 (3750 3200);
DISPLAY INVISIBLE (3750 3200);
FORCEPROP 2 LASTPIN (3650 3125) $PN 1
J 0
(3660 3135);
DISPLAY 0.808511 (3660 3135);
FORCEPROP 2 LASTPIN (3500 3125) $PN 2
J 2
(3490 3135);
DISPLAY 0.808511 (3490 3135);
FORCEPROP 2 LAST VALUE DIFF BUS_0.22UF
J 2
(3425 3125);
DISPLAY 0.553191 (3425 3125);
FORCEPROP 1 LAST CDS_LMAN_SYM_OUTLINE -25,50,25,-50
J 2
(3575 3125);
DISPLAY 0.468085 (3575 3125);
PAINT GREEN (3575 3125);
DISPLAY INVISIBLE (3575 3125);
FORCEPROP 2 LAST CDS_LIB pure_quanta
J 2
(3575 3125);
DISPLAY INVISIBLE (3575 3125);
FORCEPROP 1 LAST PIN_NAMES_ROTATE TRUE
J 2
(3575 3125);
DISPLAY 0.489362 (3575 3125);
PAINT GREEN (3575 3125);
DISPLAY INVISIBLE (3575 3125);
FORCEPROP 2 LAST VOLTAGE 6.3V
J 2
(3225 3175);
DISPLAY 0.553191 (3225 3175);
DISPLAY INVISIBLE (3225 3175);
FORCEPROP 1 LAST MATERIAL X6S
J 2
(3584 3204);
DISPLAY 0.574468 (3584 3204);
PAINT GREEN (3584 3204);
DISPLAY INVISIBLE (3584 3204);
FORCEPROP 2 LAST PACK_TYPE C0201
J 2
(3400 3175);
DISPLAY 0.553191 (3400 3175);
DISPLAY INVISIBLE (3400 3175);
FORCEPROP 2 LAST TOLERANCE 20%
J 2
(3500 3175);
DISPLAY 0.553191 (3500 3175);
DISPLAY INVISIBLE (3500 3175);
FORCEPROP 1 LAST PART_NUMBER SP_CH4221MEE01
J 2
(3459 3213);
DISPLAY 0.574468 (3459 3213);
PAINT GREEN (3459 3213);
DISPLAY INVISIBLE (3459 3213);
FORCEPROP 1 LAST LOCATION C811
J 0
(3825 3200);
DISPLAY 1.021277 (3825 3200);
DISPLAY INVISIBLE (3825 3200);
FORCEPROP 1 LAST PATH I373
J 2
(3575 3125);
DISPLAY 0.723404 (3575 3125);
DISPLAY INVISIBLE (3575 3125);
FORCEADD Q_CAP_DIFFBUS..2
R 2
(3575 3175);
FORCEPROP 1 LAST LOCATION C810
J 2
(3809 3192);
DISPLAY 0.723404 (3809 3192);
PAINT GREEN (3809 3192);
FORCEPROP 2 LAST $SEC 1
J 2
(3750 3250);
DISPLAY 0.680851 (3750 3250);
PAINT MONO (3750 3250);
DISPLAY INVISIBLE (3750 3250);
FORCEPROP 2 LAST CDS_SEC 1
J 2
(3750 3250);
DISPLAY 0.680851 (3750 3250);
DISPLAY INVISIBLE (3750 3250);
FORCEPROP 2 LASTPIN (3650 3175) $PN 1
J 0
(3660 3185);
DISPLAY 0.808511 (3660 3185);
FORCEPROP 2 LASTPIN (3500 3175) $PN 2
J 2
(3490 3185);
DISPLAY 0.808511 (3490 3185);
FORCEPROP 2 LAST VALUE DIFF BUS_0.22UF
J 2
(3425 3175);
DISPLAY 0.553191 (3425 3175);
FORCEPROP 1 LAST CDS_LMAN_SYM_OUTLINE -25,50,25,-50
J 2
(3575 3175);
DISPLAY 0.468085 (3575 3175);
PAINT GREEN (3575 3175);
DISPLAY INVISIBLE (3575 3175);
FORCEPROP 2 LAST CDS_LIB pure_quanta
J 2
(3575 3175);
DISPLAY INVISIBLE (3575 3175);
FORCEPROP 1 LAST PIN_NAMES_ROTATE TRUE
J 2
(3575 3175);
DISPLAY 0.489362 (3575 3175);
PAINT GREEN (3575 3175);
DISPLAY INVISIBLE (3575 3175);
FORCEPROP 2 LAST VOLTAGE 6.3V
J 2
(3225 3225);
DISPLAY 0.553191 (3225 3225);
DISPLAY INVISIBLE (3225 3225);
FORCEPROP 1 LAST MATERIAL X6S
J 2
(3584 3254);
DISPLAY 0.574468 (3584 3254);
PAINT GREEN (3584 3254);
DISPLAY INVISIBLE (3584 3254);
FORCEPROP 2 LAST PACK_TYPE C0201
J 2
(3400 3225);
DISPLAY 0.553191 (3400 3225);
DISPLAY INVISIBLE (3400 3225);
FORCEPROP 2 LAST TOLERANCE 20%
J 2
(3500 3225);
DISPLAY 0.553191 (3500 3225);
DISPLAY INVISIBLE (3500 3225);
FORCEPROP 1 LAST PART_NUMBER SP_CH4221MEE01
J 2
(3459 3263);
DISPLAY 0.574468 (3459 3263);
PAINT GREEN (3459 3263);
DISPLAY INVISIBLE (3459 3263);
FORCEPROP 1 LAST LOCATION C810
J 0
(3825 3250);
DISPLAY 1.021277 (3825 3250);
DISPLAY INVISIBLE (3825 3250);
FORCEPROP 1 LAST PATH I374
J 2
(3575 3175);
DISPLAY 0.723404 (3575 3175);
DISPLAY INVISIBLE (3575 3175);
FORCEADD Q_CAP_DIFFBUS..2
R 2
(3575 3325);
FORCEPROP 1 LAST LOCATION C809
J 2
(3809 3342);
DISPLAY 0.723404 (3809 3342);
PAINT GREEN (3809 3342);
FORCEPROP 2 LAST $SEC 1
J 2
(3750 3400);
DISPLAY 0.680851 (3750 3400);
PAINT MONO (3750 3400);
DISPLAY INVISIBLE (3750 3400);
FORCEPROP 2 LAST CDS_SEC 1
J 2
(3750 3400);
DISPLAY 0.680851 (3750 3400);
DISPLAY INVISIBLE (3750 3400);
FORCEPROP 2 LASTPIN (3650 3325) $PN 1
J 0
(3660 3335);
DISPLAY 0.808511 (3660 3335);
FORCEPROP 2 LASTPIN (3500 3325) $PN 2
J 2
(3490 3335);
DISPLAY 0.808511 (3490 3335);
FORCEPROP 2 LAST VALUE DIFF BUS_0.22UF
J 2
(3425 3325);
DISPLAY 0.553191 (3425 3325);
FORCEPROP 1 LAST CDS_LMAN_SYM_OUTLINE -25,50,25,-50
J 2
(3575 3325);
DISPLAY 0.468085 (3575 3325);
PAINT GREEN (3575 3325);
DISPLAY INVISIBLE (3575 3325);
FORCEPROP 2 LAST CDS_LIB pure_quanta
J 2
(3575 3325);
DISPLAY INVISIBLE (3575 3325);
FORCEPROP 1 LAST PIN_NAMES_ROTATE TRUE
J 2
(3575 3325);
DISPLAY 0.489362 (3575 3325);
PAINT GREEN (3575 3325);
DISPLAY INVISIBLE (3575 3325);
FORCEPROP 2 LAST VOLTAGE 6.3V
J 2
(3225 3375);
DISPLAY 0.553191 (3225 3375);
DISPLAY INVISIBLE (3225 3375);
FORCEPROP 1 LAST MATERIAL X6S
J 2
(3584 3404);
DISPLAY 0.574468 (3584 3404);
PAINT GREEN (3584 3404);
DISPLAY INVISIBLE (3584 3404);
FORCEPROP 2 LAST PACK_TYPE C0201
J 2
(3400 3375);
DISPLAY 0.553191 (3400 3375);
DISPLAY INVISIBLE (3400 3375);
FORCEPROP 2 LAST TOLERANCE 20%
J 2
(3500 3375);
DISPLAY 0.553191 (3500 3375);
DISPLAY INVISIBLE (3500 3375);
FORCEPROP 1 LAST PART_NUMBER SP_CH4221MEE01
J 2
(3459 3413);
DISPLAY 0.574468 (3459 3413);
PAINT GREEN (3459 3413);
DISPLAY INVISIBLE (3459 3413);
FORCEPROP 1 LAST LOCATION C809
J 0
(3825 3400);
DISPLAY 1.021277 (3825 3400);
DISPLAY INVISIBLE (3825 3400);
FORCEPROP 1 LAST PATH I375
J 2
(3575 3325);
DISPLAY 0.723404 (3575 3325);
DISPLAY INVISIBLE (3575 3325);
FORCEADD Q_CAP_DIFFBUS..2
R 2
(3575 3375);
FORCEPROP 1 LAST LOCATION C808
J 2
(3809 3392);
DISPLAY 0.723404 (3809 3392);
PAINT GREEN (3809 3392);
FORCEPROP 2 LAST $SEC 1
J 2
(3750 3450);
DISPLAY 0.680851 (3750 3450);
PAINT MONO (3750 3450);
DISPLAY INVISIBLE (3750 3450);
FORCEPROP 2 LAST CDS_SEC 1
J 2
(3750 3450);
DISPLAY 0.680851 (3750 3450);
DISPLAY INVISIBLE (3750 3450);
FORCEPROP 2 LASTPIN (3650 3375) $PN 1
J 0
(3660 3385);
DISPLAY 0.808511 (3660 3385);
FORCEPROP 2 LASTPIN (3500 3375) $PN 2
J 2
(3490 3385);
DISPLAY 0.808511 (3490 3385);
FORCEPROP 2 LAST VALUE DIFF BUS_0.22UF
J 2
(3425 3375);
DISPLAY 0.553191 (3425 3375);
FORCEPROP 1 LAST CDS_LMAN_SYM_OUTLINE -25,50,25,-50
J 2
(3575 3375);
DISPLAY 0.468085 (3575 3375);
PAINT GREEN (3575 3375);
DISPLAY INVISIBLE (3575 3375);
FORCEPROP 2 LAST CDS_LIB pure_quanta
J 2
(3575 3375);
DISPLAY INVISIBLE (3575 3375);
FORCEPROP 1 LAST PIN_NAMES_ROTATE TRUE
J 2
(3575 3375);
DISPLAY 0.489362 (3575 3375);
PAINT GREEN (3575 3375);
DISPLAY INVISIBLE (3575 3375);
FORCEPROP 2 LAST VOLTAGE 6.3V
J 2
(3225 3425);
DISPLAY 0.553191 (3225 3425);
DISPLAY INVISIBLE (3225 3425);
FORCEPROP 1 LAST MATERIAL X6S
J 2
(3584 3454);
DISPLAY 0.574468 (3584 3454);
PAINT GREEN (3584 3454);
DISPLAY INVISIBLE (3584 3454);
FORCEPROP 2 LAST PACK_TYPE C0201
J 2
(3400 3425);
DISPLAY 0.553191 (3400 3425);
DISPLAY INVISIBLE (3400 3425);
FORCEPROP 2 LAST TOLERANCE 20%
J 2
(3500 3425);
DISPLAY 0.553191 (3500 3425);
DISPLAY INVISIBLE (3500 3425);
FORCEPROP 1 LAST PART_NUMBER SP_CH4221MEE01
J 2
(3459 3463);
DISPLAY 0.574468 (3459 3463);
PAINT GREEN (3459 3463);
DISPLAY INVISIBLE (3459 3463);
FORCEPROP 1 LAST LOCATION C808
J 0
(3825 3450);
DISPLAY 1.021277 (3825 3450);
DISPLAY INVISIBLE (3825 3450);
FORCEPROP 1 LAST PATH I376
J 2
(3575 3375);
DISPLAY 0.723404 (3575 3375);
DISPLAY INVISIBLE (3575 3375);
FORCEADD Q_CAP_DIFFBUS..2
R 2
(3575 3575);
FORCEPROP 1 LAST LOCATION C806
J 2
(3809 3592);
DISPLAY 0.723404 (3809 3592);
PAINT GREEN (3809 3592);
FORCEPROP 2 LAST $SEC 1
J 2
(3750 3650);
DISPLAY 0.680851 (3750 3650);
PAINT MONO (3750 3650);
DISPLAY INVISIBLE (3750 3650);
FORCEPROP 2 LAST CDS_SEC 1
J 2
(3750 3650);
DISPLAY 0.680851 (3750 3650);
DISPLAY INVISIBLE (3750 3650);
FORCEPROP 2 LASTPIN (3650 3575) $PN 1
J 0
(3660 3585);
DISPLAY 0.808511 (3660 3585);
FORCEPROP 2 LASTPIN (3500 3575) $PN 2
J 2
(3490 3585);
DISPLAY 0.808511 (3490 3585);
FORCEPROP 2 LAST VALUE DIFF BUS_0.22UF
J 2
(3425 3575);
DISPLAY 0.553191 (3425 3575);
FORCEPROP 1 LAST MATERIAL X6S
J 2
(3534 3779);
DISPLAY 0.574468 (3534 3779);
PAINT GREEN (3534 3779);
FORCEPROP 2 LAST PACK_TYPE C0201
J 2
(3575 3725);
DISPLAY 0.553191 (3575 3725);
PAINT GREEN (3575 3725);
FORCEPROP 2 LAST VOLTAGE 6.3V
J 2
(3825 3725);
DISPLAY 0.553191 (3825 3725);
PAINT GREEN (3825 3725);
FORCEPROP 2 LAST TOLERANCE 20%
J 2
(3675 3725);
DISPLAY 0.553191 (3675 3725);
PAINT GREEN (3675 3725);
FORCEPROP 2 LAST CDS_LIB pure_quanta
J 2
(3575 3575);
DISPLAY INVISIBLE (3575 3575);
FORCEPROP 1 LAST CDS_LMAN_SYM_OUTLINE -25,50,25,-50
J 2
(3575 3575);
DISPLAY 0.468085 (3575 3575);
PAINT GREEN (3575 3575);
DISPLAY INVISIBLE (3575 3575);
FORCEPROP 1 LAST PIN_NAMES_ROTATE TRUE
J 2
(3575 3575);
DISPLAY 0.489362 (3575 3575);
PAINT GREEN (3575 3575);
DISPLAY INVISIBLE (3575 3575);
FORCEPROP 1 LAST PART_NUMBER SP_CH4221MEE01
J 2
(3834 3663);
DISPLAY 0.574468 (3834 3663);
PAINT GREEN (3834 3663);
DISPLAY INVISIBLE (3834 3663);
FORCEPROP 1 LAST LOCATION C806
J 0
(3825 3650);
DISPLAY 1.021277 (3825 3650);
DISPLAY INVISIBLE (3825 3650);
FORCEPROP 1 LAST PATH I377
J 2
(3575 3575);
DISPLAY 0.723404 (3575 3575);
DISPLAY INVISIBLE (3575 3575);
FORCEADD Q_CAP_DIFFBUS..2
R 2
(3575 3525);
FORCEPROP 1 LAST LOCATION C807
J 2
(3809 3542);
DISPLAY 0.723404 (3809 3542);
PAINT GREEN (3809 3542);
FORCEPROP 2 LAST $SEC 1
J 2
(3750 3600);
DISPLAY 0.680851 (3750 3600);
PAINT MONO (3750 3600);
DISPLAY INVISIBLE (3750 3600);
FORCEPROP 2 LAST CDS_SEC 1
J 2
(3750 3600);
DISPLAY 0.680851 (3750 3600);
DISPLAY INVISIBLE (3750 3600);
FORCEPROP 2 LASTPIN (3650 3525) $PN 1
J 0
(3660 3535);
DISPLAY 0.808511 (3660 3535);
FORCEPROP 2 LASTPIN (3500 3525) $PN 2
J 2
(3490 3535);
DISPLAY 0.808511 (3490 3535);
FORCEPROP 2 LAST VALUE DIFF BUS_0.22UF
J 2
(3425 3525);
DISPLAY 0.553191 (3425 3525);
FORCEPROP 1 LAST CDS_LMAN_SYM_OUTLINE -25,50,25,-50
J 2
(3575 3525);
DISPLAY 0.468085 (3575 3525);
PAINT GREEN (3575 3525);
DISPLAY INVISIBLE (3575 3525);
FORCEPROP 2 LAST CDS_LIB pure_quanta
J 2
(3575 3525);
DISPLAY INVISIBLE (3575 3525);
FORCEPROP 1 LAST PIN_NAMES_ROTATE TRUE
J 2
(3575 3525);
DISPLAY 0.489362 (3575 3525);
PAINT GREEN (3575 3525);
DISPLAY INVISIBLE (3575 3525);
FORCEPROP 2 LAST VOLTAGE 6.3V
J 2
(3225 3575);
DISPLAY 0.553191 (3225 3575);
DISPLAY INVISIBLE (3225 3575);
FORCEPROP 1 LAST MATERIAL X6S
J 2
(3584 3604);
DISPLAY 0.574468 (3584 3604);
PAINT GREEN (3584 3604);
DISPLAY INVISIBLE (3584 3604);
FORCEPROP 2 LAST PACK_TYPE C0201
J 2
(3400 3575);
DISPLAY 0.553191 (3400 3575);
DISPLAY INVISIBLE (3400 3575);
FORCEPROP 2 LAST TOLERANCE 20%
J 2
(3500 3575);
DISPLAY 0.553191 (3500 3575);
DISPLAY INVISIBLE (3500 3575);
FORCEPROP 1 LAST PART_NUMBER SP_CH4221MEE01
J 2
(3459 3613);
DISPLAY 0.574468 (3459 3613);
PAINT GREEN (3459 3613);
DISPLAY INVISIBLE (3459 3613);
FORCEPROP 1 LAST LOCATION C807
J 0
(3825 3600);
DISPLAY 1.021277 (3825 3600);
DISPLAY INVISIBLE (3825 3600);
FORCEPROP 1 LAST PATH I378
J 2
(3575 3525);
DISPLAY 0.723404 (3575 3525);
DISPLAY INVISIBLE (3575 3525);
FORCEADD TAP..1
(4125 200);
FORCEPROP 3 LASTPIN (4075 200) SIG_NAME P5E_CPU1_P0_TX_C_DN<0>
J 0
(4085 210);
DISPLAY 0.659574 (4085 210);
PAINT MONO (4085 210);
DISPLAY INVISIBLE (4085 210);
FORCEPROP 1 LASTPIN (4075 200) BN 0
J 0
(4063 208);
DISPLAY 0.680851 (4063 208);
PAINT GREEN (4063 208);
FORCEPROP 2 LAST CDS_LIB standard
J 0
(4125 200);
DISPLAY INVISIBLE (4125 200);
FORCEPROP 1 LAST BODY_TYPE PLUMBING
J 0
(4125 250);
DISPLAY 0.872340 (4125 250);
PAINT GREEN (4125 250);
DISPLAY INVISIBLE (4125 250);
FORCEPROP 1 LAST HDL_TAP TRUE
J 0
(4450 75);
DISPLAY 0.872340 (4450 75);
DISPLAY INVISIBLE (4450 75);
FORCEPROP 1 LAST PATH I379
J 0
(4123 200);
DISPLAY 0.872340 (4123 200);
PAINT GREEN (4123 200);
DISPLAY INVISIBLE (4123 200);
FORCEADD TAP..1
(4325 150);
FORCEPROP 3 LASTPIN (4275 150) SIG_NAME P5E_CPU1_P0_TX_C_DP<0>
J 0
(4285 160);
DISPLAY 0.659574 (4285 160);
PAINT MONO (4285 160);
DISPLAY INVISIBLE (4285 160);
FORCEPROP 1 LASTPIN (4275 150) BN 0
J 0
(4263 158);
DISPLAY 0.680851 (4263 158);
PAINT GREEN (4263 158);
FORCEPROP 2 LAST CDS_LIB standard
J 0
(4325 150);
DISPLAY INVISIBLE (4325 150);
FORCEPROP 1 LAST BODY_TYPE PLUMBING
J 0
(4325 200);
DISPLAY 0.872340 (4325 200);
PAINT GREEN (4325 200);
DISPLAY INVISIBLE (4325 200);
FORCEPROP 1 LAST HDL_TAP TRUE
J 0
(4650 25);
DISPLAY 0.872340 (4650 25);
DISPLAY INVISIBLE (4650 25);
FORCEPROP 1 LAST PATH I380
J 0
(4323 150);
DISPLAY 0.872340 (4323 150);
PAINT GREEN (4323 150);
DISPLAY INVISIBLE (4323 150);
FORCEADD TAP..1
(4125 400);
FORCEPROP 3 LASTPIN (4075 400) SIG_NAME P5E_CPU1_P0_TX_C_DN<1>
J 0
(4085 410);
DISPLAY 0.659574 (4085 410);
PAINT MONO (4085 410);
DISPLAY INVISIBLE (4085 410);
FORCEPROP 1 LASTPIN (4075 400) BN 1
J 0
(4063 408);
DISPLAY 0.680851 (4063 408);
PAINT GREEN (4063 408);
FORCEPROP 2 LAST CDS_LIB standard
J 0
(4125 400);
DISPLAY INVISIBLE (4125 400);
FORCEPROP 1 LAST BODY_TYPE PLUMBING
J 0
(4125 450);
DISPLAY 0.872340 (4125 450);
PAINT GREEN (4125 450);
DISPLAY INVISIBLE (4125 450);
FORCEPROP 1 LAST HDL_TAP TRUE
J 0
(4450 275);
DISPLAY 0.872340 (4450 275);
DISPLAY INVISIBLE (4450 275);
FORCEPROP 1 LAST PATH I381
J 0
(4123 400);
DISPLAY 0.872340 (4123 400);
PAINT GREEN (4123 400);
DISPLAY INVISIBLE (4123 400);
FORCEADD TAP..1
(4325 350);
FORCEPROP 3 LASTPIN (4275 350) SIG_NAME P5E_CPU1_P0_TX_C_DP<1>
J 0
(4285 360);
DISPLAY 0.659574 (4285 360);
PAINT MONO (4285 360);
DISPLAY INVISIBLE (4285 360);
FORCEPROP 1 LASTPIN (4275 350) BN 1
J 0
(4263 358);
DISPLAY 0.680851 (4263 358);
PAINT GREEN (4263 358);
FORCEPROP 2 LAST CDS_LIB standard
J 0
(4325 350);
DISPLAY INVISIBLE (4325 350);
FORCEPROP 1 LAST BODY_TYPE PLUMBING
J 0
(4325 400);
DISPLAY 0.872340 (4325 400);
PAINT GREEN (4325 400);
DISPLAY INVISIBLE (4325 400);
FORCEPROP 1 LAST HDL_TAP TRUE
J 0
(4650 225);
DISPLAY 0.872340 (4650 225);
DISPLAY INVISIBLE (4650 225);
FORCEPROP 1 LAST PATH I382
J 0
(4323 350);
DISPLAY 0.872340 (4323 350);
PAINT GREEN (4323 350);
DISPLAY INVISIBLE (4323 350);
FORCEADD TAP..1
(4125 600);
FORCEPROP 3 LASTPIN (4075 600) SIG_NAME P5E_CPU1_P0_TX_C_DN<2>
J 0
(4085 610);
DISPLAY 0.659574 (4085 610);
PAINT MONO (4085 610);
DISPLAY INVISIBLE (4085 610);
FORCEPROP 1 LASTPIN (4075 600) BN 2
J 0
(4063 608);
DISPLAY 0.680851 (4063 608);
PAINT GREEN (4063 608);
FORCEPROP 2 LAST CDS_LIB standard
J 0
(4125 600);
DISPLAY INVISIBLE (4125 600);
FORCEPROP 1 LAST BODY_TYPE PLUMBING
J 0
(4125 650);
DISPLAY 0.872340 (4125 650);
PAINT GREEN (4125 650);
DISPLAY INVISIBLE (4125 650);
FORCEPROP 1 LAST HDL_TAP TRUE
J 0
(4450 475);
DISPLAY 0.872340 (4450 475);
DISPLAY INVISIBLE (4450 475);
FORCEPROP 1 LAST PATH I383
J 0
(4123 600);
DISPLAY 0.872340 (4123 600);
PAINT GREEN (4123 600);
DISPLAY INVISIBLE (4123 600);
FORCEADD TAP..1
(4325 550);
FORCEPROP 3 LASTPIN (4275 550) SIG_NAME P5E_CPU1_P0_TX_C_DP<2>
J 0
(4285 560);
DISPLAY 0.659574 (4285 560);
PAINT MONO (4285 560);
DISPLAY INVISIBLE (4285 560);
FORCEPROP 1 LASTPIN (4275 550) BN 2
J 0
(4263 558);
DISPLAY 0.680851 (4263 558);
PAINT GREEN (4263 558);
FORCEPROP 2 LAST CDS_LIB standard
J 0
(4325 550);
DISPLAY INVISIBLE (4325 550);
FORCEPROP 1 LAST BODY_TYPE PLUMBING
J 0
(4325 600);
DISPLAY 0.872340 (4325 600);
PAINT GREEN (4325 600);
DISPLAY INVISIBLE (4325 600);
FORCEPROP 1 LAST HDL_TAP TRUE
J 0
(4650 425);
DISPLAY 0.872340 (4650 425);
DISPLAY INVISIBLE (4650 425);
FORCEPROP 1 LAST PATH I384
J 0
(4323 550);
DISPLAY 0.872340 (4323 550);
PAINT GREEN (4323 550);
DISPLAY INVISIBLE (4323 550);
FORCEADD TAP..1
(4325 750);
FORCEPROP 3 LASTPIN (4275 750) SIG_NAME P5E_CPU1_P0_TX_C_DP<3>
J 0
(4285 760);
DISPLAY 0.659574 (4285 760);
PAINT MONO (4285 760);
DISPLAY INVISIBLE (4285 760);
FORCEPROP 1 LASTPIN (4275 750) BN 3
J 0
(4263 758);
DISPLAY 0.680851 (4263 758);
PAINT GREEN (4263 758);
FORCEPROP 2 LAST CDS_LIB standard
J 0
(4325 750);
DISPLAY INVISIBLE (4325 750);
FORCEPROP 1 LAST BODY_TYPE PLUMBING
J 0
(4325 800);
DISPLAY 0.872340 (4325 800);
PAINT GREEN (4325 800);
DISPLAY INVISIBLE (4325 800);
FORCEPROP 1 LAST HDL_TAP TRUE
J 0
(4650 625);
DISPLAY 0.872340 (4650 625);
DISPLAY INVISIBLE (4650 625);
FORCEPROP 1 LAST PATH I385
J 0
(4323 750);
DISPLAY 0.872340 (4323 750);
PAINT GREEN (4323 750);
DISPLAY INVISIBLE (4323 750);
FORCEADD TAP..1
(4125 800);
FORCEPROP 3 LASTPIN (4075 800) SIG_NAME P5E_CPU1_P0_TX_C_DN<3>
J 0
(4085 810);
DISPLAY 0.659574 (4085 810);
PAINT MONO (4085 810);
DISPLAY INVISIBLE (4085 810);
FORCEPROP 1 LASTPIN (4075 800) BN 3
J 0
(4063 808);
DISPLAY 0.680851 (4063 808);
PAINT GREEN (4063 808);
FORCEPROP 2 LAST CDS_LIB standard
J 0
(4125 800);
DISPLAY INVISIBLE (4125 800);
FORCEPROP 1 LAST BODY_TYPE PLUMBING
J 0
(4125 850);
DISPLAY 0.872340 (4125 850);
PAINT GREEN (4125 850);
DISPLAY INVISIBLE (4125 850);
FORCEPROP 1 LAST HDL_TAP TRUE
J 0
(4450 675);
DISPLAY 0.872340 (4450 675);
DISPLAY INVISIBLE (4450 675);
FORCEPROP 1 LAST PATH I386
J 0
(4123 800);
DISPLAY 0.872340 (4123 800);
PAINT GREEN (4123 800);
DISPLAY INVISIBLE (4123 800);
FORCEADD TAP..1
(4325 950);
FORCEPROP 3 LASTPIN (4275 950) SIG_NAME P5E_CPU1_P0_TX_C_DP<4>
J 0
(4285 960);
DISPLAY 0.659574 (4285 960);
PAINT MONO (4285 960);
DISPLAY INVISIBLE (4285 960);
FORCEPROP 1 LASTPIN (4275 950) BN 4
J 0
(4263 958);
DISPLAY 0.680851 (4263 958);
PAINT GREEN (4263 958);
FORCEPROP 2 LAST CDS_LIB standard
J 0
(4325 950);
DISPLAY INVISIBLE (4325 950);
FORCEPROP 1 LAST BODY_TYPE PLUMBING
J 0
(4325 1000);
DISPLAY 0.872340 (4325 1000);
PAINT GREEN (4325 1000);
DISPLAY INVISIBLE (4325 1000);
FORCEPROP 1 LAST HDL_TAP TRUE
J 0
(4650 825);
DISPLAY 0.872340 (4650 825);
DISPLAY INVISIBLE (4650 825);
FORCEPROP 1 LAST PATH I387
J 0
(4323 950);
DISPLAY 0.872340 (4323 950);
PAINT GREEN (4323 950);
DISPLAY INVISIBLE (4323 950);
FORCEADD TAP..1
(4125 1200);
FORCEPROP 3 LASTPIN (4075 1200) SIG_NAME P5E_CPU1_P0_TX_C_DN<5>
J 0
(4085 1210);
DISPLAY 0.659574 (4085 1210);
PAINT MONO (4085 1210);
DISPLAY INVISIBLE (4085 1210);
FORCEPROP 1 LASTPIN (4075 1200) BN 5
J 0
(4063 1208);
DISPLAY 0.680851 (4063 1208);
PAINT GREEN (4063 1208);
FORCEPROP 2 LAST CDS_LIB standard
J 0
(4125 1200);
DISPLAY INVISIBLE (4125 1200);
FORCEPROP 1 LAST BODY_TYPE PLUMBING
J 0
(4125 1250);
DISPLAY 0.872340 (4125 1250);
PAINT GREEN (4125 1250);
DISPLAY INVISIBLE (4125 1250);
FORCEPROP 1 LAST HDL_TAP TRUE
J 0
(4450 1075);
DISPLAY 0.872340 (4450 1075);
DISPLAY INVISIBLE (4450 1075);
FORCEPROP 1 LAST PATH I388
J 0
(4123 1200);
DISPLAY 0.872340 (4123 1200);
PAINT GREEN (4123 1200);
DISPLAY INVISIBLE (4123 1200);
FORCEADD TAP..1
(4325 1150);
FORCEPROP 3 LASTPIN (4275 1150) SIG_NAME P5E_CPU1_P0_TX_C_DP<5>
J 0
(4285 1160);
DISPLAY 0.659574 (4285 1160);
PAINT MONO (4285 1160);
DISPLAY INVISIBLE (4285 1160);
FORCEPROP 1 LASTPIN (4275 1150) BN 5
J 0
(4263 1158);
DISPLAY 0.680851 (4263 1158);
PAINT GREEN (4263 1158);
FORCEPROP 2 LAST CDS_LIB standard
J 0
(4325 1150);
DISPLAY INVISIBLE (4325 1150);
FORCEPROP 1 LAST BODY_TYPE PLUMBING
J 0
(4325 1200);
DISPLAY 0.872340 (4325 1200);
PAINT GREEN (4325 1200);
DISPLAY INVISIBLE (4325 1200);
FORCEPROP 1 LAST HDL_TAP TRUE
J 0
(4650 1025);
DISPLAY 0.872340 (4650 1025);
DISPLAY INVISIBLE (4650 1025);
FORCEPROP 1 LAST PATH I389
J 0
(4323 1150);
DISPLAY 0.872340 (4323 1150);
PAINT GREEN (4323 1150);
DISPLAY INVISIBLE (4323 1150);
FORCEADD TAP..1
(4125 1400);
FORCEPROP 3 LASTPIN (4075 1400) SIG_NAME P5E_CPU1_P0_TX_C_DN<6>
J 0
(4085 1410);
DISPLAY 0.659574 (4085 1410);
PAINT MONO (4085 1410);
DISPLAY INVISIBLE (4085 1410);
FORCEPROP 1 LASTPIN (4075 1400) BN 6
J 0
(4063 1408);
DISPLAY 0.680851 (4063 1408);
PAINT GREEN (4063 1408);
FORCEPROP 2 LAST CDS_LIB standard
J 0
(4125 1400);
DISPLAY INVISIBLE (4125 1400);
FORCEPROP 1 LAST BODY_TYPE PLUMBING
J 0
(4125 1450);
DISPLAY 0.872340 (4125 1450);
PAINT GREEN (4125 1450);
DISPLAY INVISIBLE (4125 1450);
FORCEPROP 1 LAST HDL_TAP TRUE
J 0
(4450 1275);
DISPLAY 0.872340 (4450 1275);
DISPLAY INVISIBLE (4450 1275);
FORCEPROP 1 LAST PATH I390
J 0
(4123 1400);
DISPLAY 0.872340 (4123 1400);
PAINT GREEN (4123 1400);
DISPLAY INVISIBLE (4123 1400);
FORCEADD TAP..1
(4325 1350);
FORCEPROP 3 LASTPIN (4275 1350) SIG_NAME P5E_CPU1_P0_TX_C_DP<6>
J 0
(4285 1360);
DISPLAY 0.659574 (4285 1360);
PAINT MONO (4285 1360);
DISPLAY INVISIBLE (4285 1360);
FORCEPROP 1 LASTPIN (4275 1350) BN 6
J 0
(4263 1358);
DISPLAY 0.680851 (4263 1358);
PAINT GREEN (4263 1358);
FORCEPROP 2 LAST CDS_LIB standard
J 0
(4325 1350);
DISPLAY INVISIBLE (4325 1350);
FORCEPROP 1 LAST BODY_TYPE PLUMBING
J 0
(4325 1400);
DISPLAY 0.872340 (4325 1400);
PAINT GREEN (4325 1400);
DISPLAY INVISIBLE (4325 1400);
FORCEPROP 1 LAST HDL_TAP TRUE
J 0
(4650 1225);
DISPLAY 0.872340 (4650 1225);
DISPLAY INVISIBLE (4650 1225);
FORCEPROP 1 LAST PATH I391
J 0
(4323 1350);
DISPLAY 0.872340 (4323 1350);
PAINT GREEN (4323 1350);
DISPLAY INVISIBLE (4323 1350);
FORCEADD TAP..1
(4125 1600);
FORCEPROP 3 LASTPIN (4075 1600) SIG_NAME P5E_CPU1_P0_TX_C_DN<7>
J 0
(4085 1610);
DISPLAY 0.659574 (4085 1610);
PAINT MONO (4085 1610);
DISPLAY INVISIBLE (4085 1610);
FORCEPROP 1 LASTPIN (4075 1600) BN 7
J 0
(4063 1608);
DISPLAY 0.680851 (4063 1608);
PAINT GREEN (4063 1608);
FORCEPROP 2 LAST CDS_LIB standard
J 0
(4125 1600);
DISPLAY INVISIBLE (4125 1600);
FORCEPROP 1 LAST BODY_TYPE PLUMBING
J 0
(4125 1650);
DISPLAY 0.872340 (4125 1650);
PAINT GREEN (4125 1650);
DISPLAY INVISIBLE (4125 1650);
FORCEPROP 1 LAST HDL_TAP TRUE
J 0
(4450 1475);
DISPLAY 0.872340 (4450 1475);
DISPLAY INVISIBLE (4450 1475);
FORCEPROP 1 LAST PATH I392
J 0
(4123 1600);
DISPLAY 0.872340 (4123 1600);
PAINT GREEN (4123 1600);
DISPLAY INVISIBLE (4123 1600);
FORCEADD TAP..1
(4325 1550);
FORCEPROP 3 LASTPIN (4275 1550) SIG_NAME P5E_CPU1_P0_TX_C_DP<7>
J 0
(4285 1560);
DISPLAY 0.659574 (4285 1560);
PAINT MONO (4285 1560);
DISPLAY INVISIBLE (4285 1560);
FORCEPROP 1 LASTPIN (4275 1550) BN 7
J 0
(4263 1558);
DISPLAY 0.680851 (4263 1558);
PAINT GREEN (4263 1558);
FORCEPROP 2 LAST CDS_LIB standard
J 0
(4325 1550);
DISPLAY INVISIBLE (4325 1550);
FORCEPROP 1 LAST BODY_TYPE PLUMBING
J 0
(4325 1600);
DISPLAY 0.872340 (4325 1600);
PAINT GREEN (4325 1600);
DISPLAY INVISIBLE (4325 1600);
FORCEPROP 1 LAST HDL_TAP TRUE
J 0
(4650 1425);
DISPLAY 0.872340 (4650 1425);
DISPLAY INVISIBLE (4650 1425);
FORCEPROP 1 LAST PATH I393
J 0
(4323 1550);
DISPLAY 0.872340 (4323 1550);
PAINT GREEN (4323 1550);
DISPLAY INVISIBLE (4323 1550);
FORCEADD OFFPAGE..2
(5325 1625);
FORCEPROP 2 LAST $XR0 317 
J 0
(5514 1625);
DISPLAY 0.638298 (5514 1625);
PAINT MONO (5514 1625);
FORCEPROP 2 LAST CDS_LIB standard
J 0
(5325 1625);
DISPLAY INVISIBLE (5325 1625);
FORCEPROP 1 LAST OFFPAGE TRUE
J 0
(5650 1500);
DISPLAY 0.872340 (5650 1500);
DISPLAY INVISIBLE (5650 1500);
FORCEPROP 1 LAST COMMENT_BODY TRUE
J 0
(5280 1530);
DISPLAY 0.872340 (5280 1530);
PAINT GREEN (5280 1530);
DISPLAY INVISIBLE (5280 1530);
FORCEPROP 2 LAST PATH I394
J 0
(5525 1675);
DISPLAY 1.021277 (5525 1675);
DISPLAY INVISIBLE (5525 1675);
FORCEADD OFFPAGE..2
(5325 1575);
FORCEPROP 2 LAST $XR0 317 
J 0
(5514 1575);
DISPLAY 0.638298 (5514 1575);
PAINT MONO (5514 1575);
FORCEPROP 2 LAST CDS_LIB standard
J 0
(5325 1575);
DISPLAY INVISIBLE (5325 1575);
FORCEPROP 1 LAST OFFPAGE TRUE
J 0
(5650 1450);
DISPLAY 0.872340 (5650 1450);
DISPLAY INVISIBLE (5650 1450);
FORCEPROP 1 LAST COMMENT_BODY TRUE
J 0
(5280 1480);
DISPLAY 0.872340 (5280 1480);
PAINT GREEN (5280 1480);
DISPLAY INVISIBLE (5280 1480);
FORCEPROP 2 LAST PATH I395
J 0
(5525 1625);
DISPLAY 1.021277 (5525 1625);
DISPLAY INVISIBLE (5525 1625);
FORCEADD TAP..1
(4125 2175);
FORCEPROP 3 LASTPIN (4075 2175) SIG_NAME P5E_CPU1_P0_TX_C_DN<8>
J 0
(4085 2185);
DISPLAY 0.659574 (4085 2185);
PAINT MONO (4085 2185);
DISPLAY INVISIBLE (4085 2185);
FORCEPROP 1 LASTPIN (4075 2175) BN 8
J 0
(4063 2183);
DISPLAY 0.680851 (4063 2183);
PAINT GREEN (4063 2183);
FORCEPROP 2 LAST CDS_LIB standard
J 0
(4125 2175);
DISPLAY INVISIBLE (4125 2175);
FORCEPROP 1 LAST BODY_TYPE PLUMBING
J 0
(4125 2225);
DISPLAY 0.872340 (4125 2225);
PAINT GREEN (4125 2225);
DISPLAY INVISIBLE (4125 2225);
FORCEPROP 1 LAST HDL_TAP TRUE
J 0
(4450 2050);
DISPLAY 0.872340 (4450 2050);
DISPLAY INVISIBLE (4450 2050);
FORCEPROP 1 LAST PATH I396
J 0
(4123 2175);
DISPLAY 0.872340 (4123 2175);
PAINT GREEN (4123 2175);
DISPLAY INVISIBLE (4123 2175);
FORCEADD TAP..1
(4325 2125);
FORCEPROP 3 LASTPIN (4275 2125) SIG_NAME P5E_CPU1_P0_TX_C_DP<8>
J 0
(4285 2135);
DISPLAY 0.659574 (4285 2135);
PAINT MONO (4285 2135);
DISPLAY INVISIBLE (4285 2135);
FORCEPROP 1 LASTPIN (4275 2125) BN 8
J 0
(4263 2133);
DISPLAY 0.680851 (4263 2133);
PAINT GREEN (4263 2133);
FORCEPROP 2 LAST CDS_LIB standard
J 0
(4325 2125);
DISPLAY INVISIBLE (4325 2125);
FORCEPROP 1 LAST BODY_TYPE PLUMBING
J 0
(4325 2175);
DISPLAY 0.872340 (4325 2175);
PAINT GREEN (4325 2175);
DISPLAY INVISIBLE (4325 2175);
FORCEPROP 1 LAST HDL_TAP TRUE
J 0
(4650 2000);
DISPLAY 0.872340 (4650 2000);
DISPLAY INVISIBLE (4650 2000);
FORCEPROP 1 LAST PATH I397
J 0
(4323 2125);
DISPLAY 0.872340 (4323 2125);
PAINT GREEN (4323 2125);
DISPLAY INVISIBLE (4323 2125);
FORCEADD TAP..1
(4125 2375);
FORCEPROP 3 LASTPIN (4075 2375) SIG_NAME P5E_CPU1_P0_TX_C_DN<9>
J 0
(4085 2385);
DISPLAY 0.659574 (4085 2385);
PAINT MONO (4085 2385);
DISPLAY INVISIBLE (4085 2385);
FORCEPROP 1 LASTPIN (4075 2375) BN 9
J 0
(4063 2383);
DISPLAY 0.680851 (4063 2383);
PAINT GREEN (4063 2383);
FORCEPROP 2 LAST CDS_LIB standard
J 0
(4125 2375);
DISPLAY INVISIBLE (4125 2375);
FORCEPROP 1 LAST BODY_TYPE PLUMBING
J 0
(4125 2425);
DISPLAY 0.872340 (4125 2425);
PAINT GREEN (4125 2425);
DISPLAY INVISIBLE (4125 2425);
FORCEPROP 1 LAST HDL_TAP TRUE
J 0
(4450 2250);
DISPLAY 0.872340 (4450 2250);
DISPLAY INVISIBLE (4450 2250);
FORCEPROP 1 LAST PATH I398
J 0
(4123 2375);
DISPLAY 0.872340 (4123 2375);
PAINT GREEN (4123 2375);
DISPLAY INVISIBLE (4123 2375);
FORCEADD TAP..1
(4325 2525);
FORCEPROP 3 LASTPIN (4275 2525) SIG_NAME P5E_CPU1_P0_TX_C_DP<10>
J 0
(4285 2535);
DISPLAY 0.659574 (4285 2535);
PAINT MONO (4285 2535);
DISPLAY INVISIBLE (4285 2535);
FORCEPROP 1 LASTPIN (4275 2525) BN 10
J 0
(4263 2533);
DISPLAY 0.680851 (4263 2533);
PAINT GREEN (4263 2533);
FORCEPROP 2 LAST CDS_LIB standard
J 0
(4325 2525);
DISPLAY INVISIBLE (4325 2525);
FORCEPROP 1 LAST BODY_TYPE PLUMBING
J 0
(4325 2575);
DISPLAY 0.872340 (4325 2575);
PAINT GREEN (4325 2575);
DISPLAY INVISIBLE (4325 2575);
FORCEPROP 1 LAST HDL_TAP TRUE
J 0
(4650 2400);
DISPLAY 0.872340 (4650 2400);
DISPLAY INVISIBLE (4650 2400);
FORCEPROP 1 LAST PATH I399
J 0
(4323 2525);
DISPLAY 0.872340 (4323 2525);
PAINT GREEN (4323 2525);
DISPLAY INVISIBLE (4323 2525);
FORCEADD TAP..1
(4325 2325);
FORCEPROP 3 LASTPIN (4275 2325) SIG_NAME P5E_CPU1_P0_TX_C_DP<9>
J 0
(4285 2335);
DISPLAY 0.659574 (4285 2335);
PAINT MONO (4285 2335);
DISPLAY INVISIBLE (4285 2335);
FORCEPROP 1 LASTPIN (4275 2325) BN 9
J 0
(4263 2333);
DISPLAY 0.680851 (4263 2333);
PAINT GREEN (4263 2333);
FORCEPROP 2 LAST CDS_LIB standard
J 0
(4325 2325);
DISPLAY INVISIBLE (4325 2325);
FORCEPROP 1 LAST BODY_TYPE PLUMBING
J 0
(4325 2375);
DISPLAY 0.872340 (4325 2375);
PAINT GREEN (4325 2375);
DISPLAY INVISIBLE (4325 2375);
FORCEPROP 1 LAST HDL_TAP TRUE
J 0
(4650 2200);
DISPLAY 0.872340 (4650 2200);
DISPLAY INVISIBLE (4650 2200);
FORCEPROP 1 LAST PATH I400
J 0
(4323 2325);
DISPLAY 0.872340 (4323 2325);
PAINT GREEN (4323 2325);
DISPLAY INVISIBLE (4323 2325);
FORCEADD TAP..1
(4125 2575);
FORCEPROP 3 LASTPIN (4075 2575) SIG_NAME P5E_CPU1_P0_TX_C_DN<10>
J 0
(4085 2585);
DISPLAY 0.659574 (4085 2585);
PAINT MONO (4085 2585);
DISPLAY INVISIBLE (4085 2585);
FORCEPROP 1 LASTPIN (4075 2575) BN 10
J 0
(4063 2583);
DISPLAY 0.680851 (4063 2583);
PAINT GREEN (4063 2583);
FORCEPROP 2 LAST CDS_LIB standard
J 0
(4125 2575);
DISPLAY INVISIBLE (4125 2575);
FORCEPROP 1 LAST BODY_TYPE PLUMBING
J 0
(4125 2625);
DISPLAY 0.872340 (4125 2625);
PAINT GREEN (4125 2625);
DISPLAY INVISIBLE (4125 2625);
FORCEPROP 1 LAST HDL_TAP TRUE
J 0
(4450 2450);
DISPLAY 0.872340 (4450 2450);
DISPLAY INVISIBLE (4450 2450);
FORCEPROP 1 LAST PATH I401
J 0
(4123 2575);
DISPLAY 0.872340 (4123 2575);
PAINT GREEN (4123 2575);
DISPLAY INVISIBLE (4123 2575);
FORCEADD TAP..1
(4125 2775);
FORCEPROP 3 LASTPIN (4075 2775) SIG_NAME P5E_CPU1_P0_TX_C_DN<11>
J 0
(4085 2785);
DISPLAY 0.659574 (4085 2785);
PAINT MONO (4085 2785);
DISPLAY INVISIBLE (4085 2785);
FORCEPROP 1 LASTPIN (4075 2775) BN 11
J 0
(4063 2783);
DISPLAY 0.680851 (4063 2783);
PAINT GREEN (4063 2783);
FORCEPROP 2 LAST CDS_LIB standard
J 0
(4125 2775);
DISPLAY INVISIBLE (4125 2775);
FORCEPROP 1 LAST BODY_TYPE PLUMBING
J 0
(4125 2825);
DISPLAY 0.872340 (4125 2825);
PAINT GREEN (4125 2825);
DISPLAY INVISIBLE (4125 2825);
FORCEPROP 1 LAST HDL_TAP TRUE
J 0
(4450 2650);
DISPLAY 0.872340 (4450 2650);
DISPLAY INVISIBLE (4450 2650);
FORCEPROP 1 LAST PATH I402
J 0
(4123 2775);
DISPLAY 0.872340 (4123 2775);
PAINT GREEN (4123 2775);
DISPLAY INVISIBLE (4123 2775);
FORCEADD TAP..1
(4325 2725);
FORCEPROP 3 LASTPIN (4275 2725) SIG_NAME P5E_CPU1_P0_TX_C_DP<11>
J 0
(4285 2735);
DISPLAY 0.659574 (4285 2735);
PAINT MONO (4285 2735);
DISPLAY INVISIBLE (4285 2735);
FORCEPROP 1 LASTPIN (4275 2725) BN 11
J 0
(4263 2733);
DISPLAY 0.680851 (4263 2733);
PAINT GREEN (4263 2733);
FORCEPROP 2 LAST CDS_LIB standard
J 0
(4325 2725);
DISPLAY INVISIBLE (4325 2725);
FORCEPROP 1 LAST BODY_TYPE PLUMBING
J 0
(4325 2775);
DISPLAY 0.872340 (4325 2775);
PAINT GREEN (4325 2775);
DISPLAY INVISIBLE (4325 2775);
FORCEPROP 1 LAST HDL_TAP TRUE
J 0
(4650 2600);
DISPLAY 0.872340 (4650 2600);
DISPLAY INVISIBLE (4650 2600);
FORCEPROP 1 LAST PATH I403
J 0
(4323 2725);
DISPLAY 0.872340 (4323 2725);
PAINT GREEN (4323 2725);
DISPLAY INVISIBLE (4323 2725);
FORCEADD TAP..1
(4125 2975);
FORCEPROP 3 LASTPIN (4075 2975) SIG_NAME P5E_CPU1_P0_TX_C_DN<12>
J 0
(4085 2985);
DISPLAY 0.659574 (4085 2985);
PAINT MONO (4085 2985);
DISPLAY INVISIBLE (4085 2985);
FORCEPROP 1 LASTPIN (4075 2975) BN 12
J 0
(4063 2983);
DISPLAY 0.680851 (4063 2983);
PAINT GREEN (4063 2983);
FORCEPROP 2 LAST CDS_LIB standard
J 0
(4125 2975);
DISPLAY INVISIBLE (4125 2975);
FORCEPROP 1 LAST BODY_TYPE PLUMBING
J 0
(4125 3025);
DISPLAY 0.872340 (4125 3025);
PAINT GREEN (4125 3025);
DISPLAY INVISIBLE (4125 3025);
FORCEPROP 1 LAST HDL_TAP TRUE
J 0
(4450 2850);
DISPLAY 0.872340 (4450 2850);
DISPLAY INVISIBLE (4450 2850);
FORCEPROP 1 LAST PATH I404
J 0
(4123 2975);
DISPLAY 0.872340 (4123 2975);
PAINT GREEN (4123 2975);
DISPLAY INVISIBLE (4123 2975);
FORCEADD TAP..1
(4325 2925);
FORCEPROP 3 LASTPIN (4275 2925) SIG_NAME P5E_CPU1_P0_TX_C_DP<12>
J 0
(4285 2935);
DISPLAY 0.659574 (4285 2935);
PAINT MONO (4285 2935);
DISPLAY INVISIBLE (4285 2935);
FORCEPROP 1 LASTPIN (4275 2925) BN 12
J 0
(4263 2933);
DISPLAY 0.680851 (4263 2933);
PAINT GREEN (4263 2933);
FORCEPROP 2 LAST CDS_LIB standard
J 0
(4325 2925);
DISPLAY INVISIBLE (4325 2925);
FORCEPROP 1 LAST BODY_TYPE PLUMBING
J 0
(4325 2975);
DISPLAY 0.872340 (4325 2975);
PAINT GREEN (4325 2975);
DISPLAY INVISIBLE (4325 2975);
FORCEPROP 1 LAST HDL_TAP TRUE
J 0
(4650 2800);
DISPLAY 0.872340 (4650 2800);
DISPLAY INVISIBLE (4650 2800);
FORCEPROP 1 LAST PATH I405
J 0
(4323 2925);
DISPLAY 0.872340 (4323 2925);
PAINT GREEN (4323 2925);
DISPLAY INVISIBLE (4323 2925);
FORCEADD TAP..1
(4125 3175);
FORCEPROP 3 LASTPIN (4075 3175) SIG_NAME P5E_CPU1_P0_TX_C_DN<13>
J 0
(4085 3185);
DISPLAY 0.659574 (4085 3185);
PAINT MONO (4085 3185);
DISPLAY INVISIBLE (4085 3185);
FORCEPROP 1 LASTPIN (4075 3175) BN 13
J 0
(4063 3183);
DISPLAY 0.680851 (4063 3183);
PAINT GREEN (4063 3183);
FORCEPROP 2 LAST CDS_LIB standard
J 0
(4125 3175);
DISPLAY INVISIBLE (4125 3175);
FORCEPROP 1 LAST BODY_TYPE PLUMBING
J 0
(4125 3225);
DISPLAY 0.872340 (4125 3225);
PAINT GREEN (4125 3225);
DISPLAY INVISIBLE (4125 3225);
FORCEPROP 1 LAST HDL_TAP TRUE
J 0
(4450 3050);
DISPLAY 0.872340 (4450 3050);
DISPLAY INVISIBLE (4450 3050);
FORCEPROP 1 LAST PATH I406
J 0
(4123 3175);
DISPLAY 0.872340 (4123 3175);
PAINT GREEN (4123 3175);
DISPLAY INVISIBLE (4123 3175);
FORCEADD TAP..1
(4325 3125);
FORCEPROP 3 LASTPIN (4275 3125) SIG_NAME P5E_CPU1_P0_TX_C_DP<13>
J 0
(4285 3135);
DISPLAY 0.659574 (4285 3135);
PAINT MONO (4285 3135);
DISPLAY INVISIBLE (4285 3135);
FORCEPROP 1 LASTPIN (4275 3125) BN 13
J 0
(4263 3133);
DISPLAY 0.680851 (4263 3133);
PAINT GREEN (4263 3133);
FORCEPROP 2 LAST CDS_LIB standard
J 0
(4325 3125);
DISPLAY INVISIBLE (4325 3125);
FORCEPROP 1 LAST BODY_TYPE PLUMBING
J 0
(4325 3175);
DISPLAY 0.872340 (4325 3175);
PAINT GREEN (4325 3175);
DISPLAY INVISIBLE (4325 3175);
FORCEPROP 1 LAST HDL_TAP TRUE
J 0
(4650 3000);
DISPLAY 0.872340 (4650 3000);
DISPLAY INVISIBLE (4650 3000);
FORCEPROP 1 LAST PATH I407
J 0
(4323 3125);
DISPLAY 0.872340 (4323 3125);
PAINT GREEN (4323 3125);
DISPLAY INVISIBLE (4323 3125);
FORCEADD TAP..1
(4325 3325);
FORCEPROP 3 LASTPIN (4275 3325) SIG_NAME P5E_CPU1_P0_TX_C_DP<14>
J 0
(4285 3335);
DISPLAY 0.659574 (4285 3335);
PAINT MONO (4285 3335);
DISPLAY INVISIBLE (4285 3335);
FORCEPROP 1 LASTPIN (4275 3325) BN 14
J 0
(4263 3333);
DISPLAY 0.680851 (4263 3333);
PAINT GREEN (4263 3333);
FORCEPROP 2 LAST CDS_LIB standard
J 0
(4325 3325);
DISPLAY INVISIBLE (4325 3325);
FORCEPROP 1 LAST BODY_TYPE PLUMBING
J 0
(4325 3375);
DISPLAY 0.872340 (4325 3375);
PAINT GREEN (4325 3375);
DISPLAY INVISIBLE (4325 3375);
FORCEPROP 1 LAST HDL_TAP TRUE
J 0
(4650 3200);
DISPLAY 0.872340 (4650 3200);
DISPLAY INVISIBLE (4650 3200);
FORCEPROP 1 LAST PATH I408
J 0
(4323 3325);
DISPLAY 0.872340 (4323 3325);
PAINT GREEN (4323 3325);
DISPLAY INVISIBLE (4323 3325);
FORCEADD TAP..1
(4125 3575);
FORCEPROP 3 LASTPIN (4075 3575) SIG_NAME P5E_CPU1_P0_TX_C_DN<15>
J 0
(4085 3585);
DISPLAY 0.659574 (4085 3585);
PAINT MONO (4085 3585);
DISPLAY INVISIBLE (4085 3585);
FORCEPROP 1 LASTPIN (4075 3575) BN 15
J 0
(4063 3583);
DISPLAY 0.680851 (4063 3583);
PAINT GREEN (4063 3583);
FORCEPROP 2 LAST CDS_LIB standard
J 0
(4125 3575);
DISPLAY INVISIBLE (4125 3575);
FORCEPROP 1 LAST BODY_TYPE PLUMBING
J 0
(4125 3625);
DISPLAY 0.872340 (4125 3625);
PAINT GREEN (4125 3625);
DISPLAY INVISIBLE (4125 3625);
FORCEPROP 1 LAST HDL_TAP TRUE
J 0
(4450 3450);
DISPLAY 0.872340 (4450 3450);
DISPLAY INVISIBLE (4450 3450);
FORCEPROP 1 LAST PATH I409
J 0
(4123 3575);
DISPLAY 0.872340 (4123 3575);
PAINT GREEN (4123 3575);
DISPLAY INVISIBLE (4123 3575);
FORCEADD TAP..1
(4125 3375);
FORCEPROP 3 LASTPIN (4075 3375) SIG_NAME P5E_CPU1_P0_TX_C_DN<14>
J 0
(4085 3385);
DISPLAY 0.659574 (4085 3385);
PAINT MONO (4085 3385);
DISPLAY INVISIBLE (4085 3385);
FORCEPROP 1 LASTPIN (4075 3375) BN 14
J 0
(4063 3383);
DISPLAY 0.680851 (4063 3383);
PAINT GREEN (4063 3383);
FORCEPROP 2 LAST CDS_LIB standard
J 0
(4125 3375);
DISPLAY INVISIBLE (4125 3375);
FORCEPROP 1 LAST BODY_TYPE PLUMBING
J 0
(4125 3425);
DISPLAY 0.872340 (4125 3425);
PAINT GREEN (4125 3425);
DISPLAY INVISIBLE (4125 3425);
FORCEPROP 1 LAST HDL_TAP TRUE
J 0
(4450 3250);
DISPLAY 0.872340 (4450 3250);
DISPLAY INVISIBLE (4450 3250);
FORCEPROP 1 LAST PATH I410
J 0
(4123 3375);
DISPLAY 0.872340 (4123 3375);
PAINT GREEN (4123 3375);
DISPLAY INVISIBLE (4123 3375);
FORCEADD TAP..1
(4325 3525);
FORCEPROP 3 LASTPIN (4275 3525) SIG_NAME P5E_CPU1_P0_TX_C_DP<15>
J 0
(4285 3535);
DISPLAY 0.659574 (4285 3535);
PAINT MONO (4285 3535);
DISPLAY INVISIBLE (4285 3535);
FORCEPROP 1 LASTPIN (4275 3525) BN 15
J 0
(4263 3533);
DISPLAY 0.680851 (4263 3533);
PAINT GREEN (4263 3533);
FORCEPROP 2 LAST CDS_LIB standard
J 0
(4325 3525);
DISPLAY INVISIBLE (4325 3525);
FORCEPROP 1 LAST BODY_TYPE PLUMBING
J 0
(4325 3575);
DISPLAY 0.872340 (4325 3575);
PAINT GREEN (4325 3575);
DISPLAY INVISIBLE (4325 3575);
FORCEPROP 1 LAST HDL_TAP TRUE
J 0
(4650 3400);
DISPLAY 0.872340 (4650 3400);
DISPLAY INVISIBLE (4650 3400);
FORCEPROP 1 LAST PATH I411
J 0
(4323 3525);
DISPLAY 0.872340 (4323 3525);
PAINT GREEN (4323 3525);
DISPLAY INVISIBLE (4323 3525);
FORCEADD OFFPAGE..2
(5325 3550);
FORCEPROP 2 LAST $XR0 317 
J 0
(5514 3550);
DISPLAY 0.638298 (5514 3550);
PAINT MONO (5514 3550);
FORCEPROP 2 LAST CDS_LIB standard
J 0
(5325 3550);
DISPLAY INVISIBLE (5325 3550);
FORCEPROP 1 LAST OFFPAGE TRUE
J 0
(5650 3425);
DISPLAY 0.872340 (5650 3425);
DISPLAY INVISIBLE (5650 3425);
FORCEPROP 1 LAST COMMENT_BODY TRUE
J 0
(5280 3455);
DISPLAY 0.872340 (5280 3455);
PAINT GREEN (5280 3455);
DISPLAY INVISIBLE (5280 3455);
FORCEPROP 2 LAST PATH I412
J 0
(5525 3600);
DISPLAY 1.021277 (5525 3600);
DISPLAY INVISIBLE (5525 3600);
FORCEADD OFFPAGE..2
(5325 3600);
FORCEPROP 2 LAST $XR0 317 
J 0
(5514 3600);
DISPLAY 0.638298 (5514 3600);
PAINT MONO (5514 3600);
FORCEPROP 2 LAST CDS_LIB standard
J 0
(5325 3600);
DISPLAY INVISIBLE (5325 3600);
FORCEPROP 1 LAST OFFPAGE TRUE
J 0
(5650 3475);
DISPLAY 0.872340 (5650 3475);
DISPLAY INVISIBLE (5650 3475);
FORCEPROP 1 LAST COMMENT_BODY TRUE
J 0
(5280 3505);
DISPLAY 0.872340 (5280 3505);
PAINT GREEN (5280 3505);
DISPLAY INVISIBLE (5280 3505);
FORCEPROP 2 LAST PATH I413
J 0
(5525 3650);
DISPLAY 1.021277 (5525 3650);
DISPLAY INVISIBLE (5525 3650);
FORCEADD TAP..1
(4125 1000);
FORCEPROP 3 LASTPIN (4075 1000) SIG_NAME P5E_CPU1_P0_TX_C_DN<4>
J 0
(4085 1010);
DISPLAY 0.659574 (4085 1010);
PAINT MONO (4085 1010);
DISPLAY INVISIBLE (4085 1010);
FORCEPROP 1 LASTPIN (4075 1000) BN 4
J 0
(4063 1008);
DISPLAY 0.680851 (4063 1008);
PAINT GREEN (4063 1008);
FORCEPROP 2 LAST CDS_LIB standard
J 0
(4125 1000);
DISPLAY INVISIBLE (4125 1000);
FORCEPROP 1 LAST BODY_TYPE PLUMBING
J 0
(4125 1050);
DISPLAY 0.872340 (4125 1050);
PAINT GREEN (4125 1050);
DISPLAY INVISIBLE (4125 1050);
FORCEPROP 1 LAST HDL_TAP TRUE
J 0
(4450 875);
DISPLAY 0.872340 (4450 875);
DISPLAY INVISIBLE (4450 875);
FORCEPROP 1 LAST PATH I414
J 0
(4123 1000);
DISPLAY 0.872340 (4123 1000);
PAINT GREEN (4123 1000);
DISPLAY INVISIBLE (4123 1000);
FORCEADD Q_CAP_DIFFBUS..2
R 2
(3575 1350);
FORCEPROP 1 LAST LOCATION C825
J 2
(3809 1367);
DISPLAY 0.723404 (3809 1367);
PAINT GREEN (3809 1367);
FORCEPROP 2 LAST $SEC 1
J 2
(3750 1425);
DISPLAY 0.680851 (3750 1425);
PAINT MONO (3750 1425);
DISPLAY INVISIBLE (3750 1425);
FORCEPROP 2 LAST CDS_SEC 1
J 2
(3750 1425);
DISPLAY 0.680851 (3750 1425);
DISPLAY INVISIBLE (3750 1425);
FORCEPROP 2 LASTPIN (3650 1350) $PN 1
J 0
(3660 1360);
DISPLAY 0.808511 (3660 1360);
FORCEPROP 2 LASTPIN (3500 1350) $PN 2
J 2
(3490 1360);
DISPLAY 0.808511 (3490 1360);
FORCEPROP 2 LAST VALUE DIFF BUS_0.22UF
J 2
(3425 1350);
DISPLAY 0.553191 (3425 1350);
FORCEPROP 1 LAST PIN_NAMES_ROTATE TRUE
J 2
(3575 1350);
DISPLAY 0.489362 (3575 1350);
PAINT GREEN (3575 1350);
DISPLAY INVISIBLE (3575 1350);
FORCEPROP 2 LAST CDS_LIB pure_quanta
J 2
(3575 1350);
DISPLAY INVISIBLE (3575 1350);
FORCEPROP 1 LAST CDS_LMAN_SYM_OUTLINE -25,50,25,-50
J 2
(3575 1350);
DISPLAY 0.468085 (3575 1350);
PAINT GREEN (3575 1350);
DISPLAY INVISIBLE (3575 1350);
FORCEPROP 2 LAST VOLTAGE 6.3V
J 2
(3225 1400);
DISPLAY 0.553191 (3225 1400);
DISPLAY INVISIBLE (3225 1400);
FORCEPROP 1 LAST MATERIAL X6S
J 2
(3584 1429);
DISPLAY 0.574468 (3584 1429);
PAINT GREEN (3584 1429);
DISPLAY INVISIBLE (3584 1429);
FORCEPROP 2 LAST PACK_TYPE C0201
J 2
(3400 1400);
DISPLAY 0.553191 (3400 1400);
DISPLAY INVISIBLE (3400 1400);
FORCEPROP 2 LAST TOLERANCE 20%
J 2
(3500 1400);
DISPLAY 0.553191 (3500 1400);
DISPLAY INVISIBLE (3500 1400);
FORCEPROP 1 LAST PART_NUMBER SP_CH4221MEE01
J 2
(3459 1438);
DISPLAY 0.574468 (3459 1438);
PAINT GREEN (3459 1438);
DISPLAY INVISIBLE (3459 1438);
FORCEPROP 1 LAST LOCATION C825
J 0
(3825 1425);
DISPLAY 1.021277 (3825 1425);
DISPLAY INVISIBLE (3825 1425);
FORCEPROP 1 LAST PATH I415
J 2
(3575 1350);
DISPLAY 0.723404 (3575 1350);
DISPLAY INVISIBLE (3575 1350);
FORCEADD Q_CAP_DIFFBUS..2
R 2
(3575 1400);
FORCEPROP 1 LAST LOCATION C824
J 2
(3809 1417);
DISPLAY 0.723404 (3809 1417);
PAINT GREEN (3809 1417);
FORCEPROP 2 LAST $SEC 1
J 2
(3750 1475);
DISPLAY 0.680851 (3750 1475);
PAINT MONO (3750 1475);
DISPLAY INVISIBLE (3750 1475);
FORCEPROP 2 LAST CDS_SEC 1
J 2
(3750 1475);
DISPLAY 0.680851 (3750 1475);
DISPLAY INVISIBLE (3750 1475);
FORCEPROP 2 LASTPIN (3650 1400) $PN 1
J 0
(3660 1410);
DISPLAY 0.808511 (3660 1410);
FORCEPROP 2 LASTPIN (3500 1400) $PN 2
J 2
(3490 1410);
DISPLAY 0.808511 (3490 1410);
FORCEPROP 2 LAST VALUE DIFF BUS_0.22UF
J 2
(3425 1400);
DISPLAY 0.553191 (3425 1400);
FORCEPROP 1 LAST PIN_NAMES_ROTATE TRUE
J 2
(3575 1400);
DISPLAY 0.489362 (3575 1400);
PAINT GREEN (3575 1400);
DISPLAY INVISIBLE (3575 1400);
FORCEPROP 2 LAST CDS_LIB pure_quanta
J 2
(3575 1400);
DISPLAY INVISIBLE (3575 1400);
FORCEPROP 1 LAST CDS_LMAN_SYM_OUTLINE -25,50,25,-50
J 2
(3575 1400);
DISPLAY 0.468085 (3575 1400);
PAINT GREEN (3575 1400);
DISPLAY INVISIBLE (3575 1400);
FORCEPROP 2 LAST VOLTAGE 6.3V
J 2
(3225 1450);
DISPLAY 0.553191 (3225 1450);
DISPLAY INVISIBLE (3225 1450);
FORCEPROP 1 LAST MATERIAL X6S
J 2
(3584 1479);
DISPLAY 0.574468 (3584 1479);
PAINT GREEN (3584 1479);
DISPLAY INVISIBLE (3584 1479);
FORCEPROP 2 LAST PACK_TYPE C0201
J 2
(3400 1450);
DISPLAY 0.553191 (3400 1450);
DISPLAY INVISIBLE (3400 1450);
FORCEPROP 2 LAST TOLERANCE 20%
J 2
(3500 1450);
DISPLAY 0.553191 (3500 1450);
DISPLAY INVISIBLE (3500 1450);
FORCEPROP 1 LAST PART_NUMBER SP_CH4221MEE01
J 2
(3459 1488);
DISPLAY 0.574468 (3459 1488);
PAINT GREEN (3459 1488);
DISPLAY INVISIBLE (3459 1488);
FORCEPROP 1 LAST LOCATION C824
J 0
(3825 1475);
DISPLAY 1.021277 (3825 1475);
DISPLAY INVISIBLE (3825 1475);
FORCEPROP 1 LAST PATH I416
J 2
(3575 1400);
DISPLAY 0.723404 (3575 1400);
DISPLAY INVISIBLE (3575 1400);
FORCEADD QUANTA_TITLE_BLOCK_C..1
(5900 -1700);
FORCEPROP 0 LAST CDS_CON_LAST_MODIFIED Thu Sep 14 16:12:29 2023
J 0
(4015 -1685);
DISPLAY INVISIBLE (4015 -1685);
FORCEPROP 1 LAST CUSTOM_TXT_CDS <CON_LAST_MODIFIED>
J 0
(4015 -1685);
DISPLAY 0.978723 (4015 -1685);
FORCEPROP 2 LAST CUSTOM_TXT_CDS <XR_PAGE_TITLE>
J 0
(-1990 3550);
DISPLAY 0.638298 (-1990 3550);
PAINT PINK (-1990 3550);
DISPLAY INVISIBLE (-1990 3550);
FORCEPROP 2 LAST CUSTOM_TXT_CDS <Q_NUMBER>
J 0
(4497 -1597);
DISPLAY 1.212766 (4497 -1597);
FORCEPROP 1 LAST CUSTOM_TXT_CDS <NAME_2>
J 0
(2725 -1650);
FORCEPROP 1 LAST CUSTOM_TXT_CDS <NAME_1>
J 0
(2725 -1525);
FORCEPROP 1 LAST CUSTOM_TXT_CDS <Q_PROJ>
J 0
(3518 -1598);
DISPLAY 1.212766 (3518 -1598);
FORCEPROP 1 LAST CUSTOM_TXT_CDS <Q_REV>
J 0
(5716 -1597);
DISPLAY 1.212766 (5716 -1597);
FORCEPROP 1 LAST CUSTOM_TXT_CDS <CON_PAGE_NUM> OF <CON_TOTAL_PAGES>
J 0
(5454 -1682);
DISPLAY 0.978723 (5454 -1682);
FORCEPROP 1 LAST Q_TITLE PCIE AC-COUPLE CAPS 3/5
J 0
(-3466 -1674);
DISPLAY 2.446809 (-3466 -1674);
PAINT GREEN (-3466 -1674);
FORCEPROP 2 LAST CDS_LIB pure_quanta
J 0
(5900 -1700);
DISPLAY INVISIBLE (5900 -1700);
FORCEPROP 1 LAST CDS_LMAN_SYM_OUTLINE -9475,6775,100,-125
J 0
(5900 -1700);
DISPLAY 0.468085 (5900 -1700);
PAINT GREEN (5900 -1700);
DISPLAY INVISIBLE (5900 -1700);
FORCEPROP 2 LAST PAGE_BORDER TRUE
J 0
(-1990 3550);
DISPLAY 0.638298 (-1990 3550);
PAINT PINK (-1990 3550);
DISPLAY INVISIBLE (-1990 3550);
FORCEPROP 2 LAST CDS_XR_PAGE_TITLE CR-65 : @T6G_MB_LIB.T6G(SCH_1):PAGE65
J 0
(-1990 3550);
DISPLAY 0.638298 (-1990 3550);
PAINT PINK (-1990 3550);
DISPLAY INVISIBLE (-1990 3550);
FORCEPROP 1 LAST COMMENT_BODY TRUE
J 0
(5912 -1713);
DISPLAY 0.978723 (5912 -1713);
PAINT GREEN (5912 -1713);
DISPLAY INVISIBLE (5912 -1713);
FORCEPROP 1 LAST Q_DEPT CCBU
J 1
(2137 -1651);
DISPLAY 1.957447 (2137 -1651);
PAINT GREEN (2137 -1651);
DISPLAY INVISIBLE (2137 -1651);
WIRE 17 -1 (4175 2400)(4175 2200);
WIRE 17 -1 (4175 2600)(4175 2400);
WIRE 17 -1 (4175 2800)(4175 2600);
WIRE 17 -1 (4175 2800)(4175 3000);
WIRE 17 -1 (4175 3200)(4175 3000);
WIRE 17 -1 (4175 3400)(4175 3200);
WIRE 17 -1 (4175 3600)(4175 3400);
WIRE 17 -1 (4175 3600)(5275 3600);
FORCEPROP 2 LAST SIG_NAME P5E_CPU1_P0_TX_C_DN<15:8>
J 0
(4415 3610);
DISPLAY 0.680851 (4415 3610);
PAINT WHITE (4415 3610);
WIRE 17 -1 (4375 2750)(4375 2950);
WIRE 17 -1 (4375 2750)(4375 2550);
WIRE 17 -1 (4375 3150)(4375 2950);
WIRE 17 -1 (4375 3350)(4375 3150);
WIRE 17 -1 (4375 2550)(4375 2350);
WIRE 17 -1 (4375 2350)(4375 2150);
WIRE 17 -1 (4375 3550)(4375 3350);
WIRE 17 -1 (4375 3550)(5275 3550);
FORCEPROP 2 LAST SIG_NAME P5E_CPU1_P0_TX_C_DP<15:8>
J 0
(4415 3560);
DISPLAY 0.680851 (4415 3560);
PAINT WHITE (4415 3560);
WIRE 17 -1 (2800 2400)(2800 2200);
WIRE 17 -1 (2800 2600)(2800 2400);
WIRE 17 -1 (2800 2800)(2800 2600);
WIRE 17 -1 (2800 2800)(2800 3000);
WIRE 17 -1 (2800 3200)(2800 3000);
WIRE 17 -1 (2800 3400)(2800 3200);
WIRE 17 -1 (2800 3600)(2800 3400);
WIRE 17 -1 (1700 3600)(2800 3600);
FORCEPROP 2 LAST SIG_NAME P5E_CPU1_P0_TX_DN<15:8>
J 0
(1740 3610);
DISPLAY 0.680851 (1740 3610);
PAINT WHITE (1740 3610);
WIRE 17 -1 (2550 2150)(2550 2350);
WIRE 17 -1 (2550 2350)(2550 2550);
WIRE 17 -1 (2550 2550)(2550 2750);
WIRE 17 -1 (2550 2750)(2550 2950);
WIRE 17 -1 (2550 2950)(2550 3150);
WIRE 17 -1 (2550 3150)(2550 3350);
WIRE 17 -1 (2550 3350)(2550 3550);
WIRE 17 -1 (1700 3550)(2550 3550);
FORCEPROP 2 LAST SIG_NAME P5E_CPU1_P0_TX_DP<15:8>
J 0
(1740 3560);
DISPLAY 0.680851 (1740 3560);
PAINT WHITE (1740 3560);
WIRE 17 -1 (2550 1375)(2550 1575);
WIRE 17 -1 (2550 1175)(2550 1375);
WIRE 17 -1 (1700 1575)(2550 1575);
FORCEPROP 2 LAST SIG_NAME P5E_CPU1_P0_TX_DP<7:0>
J 0
(1740 1585);
DISPLAY 0.680851 (1740 1585);
PAINT WHITE (1740 1585);
WIRE 17 -1 (2550 975)(2550 1175);
WIRE 17 -1 (2800 825)(2800 1025);
WIRE 17 -1 (2800 825)(2800 625);
WIRE 17 -1 (2800 1225)(2800 1025);
WIRE 17 -1 (2800 1425)(2800 1225);
WIRE 17 -1 (2800 625)(2800 425);
WIRE 17 -1 (2800 425)(2800 225);
WIRE 17 -1 (2800 1625)(2800 1425);
WIRE 17 -1 (1700 1625)(2800 1625);
FORCEPROP 2 LAST SIG_NAME P5E_CPU1_P0_TX_DN<7:0>
J 0
(1740 1635);
DISPLAY 0.680851 (1740 1635);
PAINT WHITE (1740 1635);
WIRE 17 -1 (2550 575)(2550 775);
WIRE 17 -1 (2550 375)(2550 575);
WIRE 17 -1 (2550 775)(2550 975);
WIRE 17 -1 (2550 175)(2550 375);
WIRE 17 -1 (-125 1575)(775 1575);
FORCEPROP 2 LAST SIG_NAME P5E_CPU0_G3_TX_C_DP<7:0>
J 0
(-85 1585);
DISPLAY 0.680851 (-85 1585);
PAINT WHITE (-85 1585);
WIRE 17 -1 (-1950 2150)(-1950 2350);
WIRE 17 -1 (-1950 2350)(-1950 2550);
WIRE 17 -1 (-1950 2550)(-1950 2750);
WIRE 17 -1 (-1950 2750)(-1950 2950);
WIRE 17 -1 (-1950 2950)(-1950 3150);
WIRE 17 -1 (-1950 3150)(-1950 3350);
WIRE 17 -1 (-1950 3350)(-1950 3550);
WIRE 17 -1 (-2800 3550)(-1950 3550);
FORCEPROP 2 LAST SIG_NAME P5E_CPU0_G3_TX_DP<15:8>
J 0
(-2760 3560);
DISPLAY 0.680851 (-2760 3560);
PAINT WHITE (-2760 3560);
WIRE 17 -1 (-125 3150)(-125 2950);
WIRE 17 -1 (-125 3350)(-125 3150);
WIRE 17 -1 (-125 2750)(-125 2950);
WIRE 17 -1 (-125 2750)(-125 2550);
WIRE 17 -1 (-125 3550)(-125 3350);
WIRE 17 -1 (-125 3550)(775 3550);
FORCEPROP 2 LAST SIG_NAME P5E_CPU0_G3_TX_C_DP<15:8>
J 0
(-85 3560);
DISPLAY 0.680851 (-85 3560);
PAINT WHITE (-85 3560);
WIRE 17 -1 (-125 2550)(-125 2350);
WIRE 17 -1 (-125 2350)(-125 2150);
WIRE 17 -1 (-125 1575)(-125 1375);
WIRE 17 -1 (-125 1375)(-125 1175);
WIRE 17 -1 (-125 1175)(-125 975);
WIRE 17 -1 (-125 775)(-125 975);
WIRE 17 -1 (-125 575)(-125 375);
WIRE 17 -1 (-125 775)(-125 575);
WIRE 17 -1 (-125 375)(-125 175);
WIRE 17 -1 (4375 375)(4375 175);
WIRE 17 -1 (4375 575)(4375 375);
WIRE 17 -1 (4375 775)(4375 575);
WIRE 17 -1 (4375 775)(4375 975);
WIRE 17 -1 (4375 1175)(4375 975);
WIRE 17 -1 (4375 1375)(4375 1175);
WIRE 17 -1 (4375 1575)(4375 1375);
WIRE 17 -1 (4375 1575)(5275 1575);
FORCEPROP 2 LAST SIG_NAME P5E_CPU1_P0_TX_C_DP<7:0>
J 0
(4415 1585);
DISPLAY 0.680851 (4415 1585);
PAINT WHITE (4415 1585);
WIRE 17 -1 (4175 425)(4175 225);
WIRE 17 -1 (4175 625)(4175 425);
WIRE 17 -1 (4175 825)(4175 625);
WIRE 17 -1 (4175 825)(4175 1025);
WIRE 17 -1 (4175 1225)(4175 1025);
WIRE 17 -1 (4175 1425)(4175 1225);
WIRE 17 -1 (4175 1625)(4175 1425);
WIRE 17 -1 (4175 1625)(5275 1625);
FORCEPROP 2 LAST SIG_NAME P5E_CPU1_P0_TX_C_DN<7:0>
J 0
(4415 1635);
DISPLAY 0.680851 (4415 1635);
PAINT WHITE (4415 1635);
WIRE 17 -1 (-1950 375)(-1950 575);
WIRE 17 -1 (-1950 175)(-1950 375);
WIRE 17 -1 (-1950 575)(-1950 775);
WIRE 17 -1 (-1950 775)(-1950 975);
WIRE 17 -1 (-1950 975)(-1950 1175);
WIRE 17 -1 (-1950 1175)(-1950 1375);
WIRE 17 -1 (-1950 1375)(-1950 1575);
WIRE 17 -1 (-2800 1575)(-1950 1575);
FORCEPROP 2 LAST SIG_NAME P5E_CPU0_G3_TX_DP<7:0>
J 0
(-2760 1585);
DISPLAY 0.680851 (-2760 1585);
PAINT WHITE (-2760 1585);
WIRE 17 -1 (-325 625)(-325 425);
WIRE 17 -1 (-325 825)(-325 625);
WIRE 17 -1 (-325 425)(-325 225);
WIRE 17 -1 (-325 825)(-325 1025);
WIRE 17 -1 (-325 1225)(-325 1025);
WIRE 17 -1 (-325 1425)(-325 1225);
WIRE 17 -1 (-325 1625)(-325 1425);
WIRE 17 -1 (-325 1625)(775 1625);
FORCEPROP 2 LAST SIG_NAME P5E_CPU0_G3_TX_C_DN<7:0>
J 0
(-85 1635);
DISPLAY 0.680851 (-85 1635);
PAINT WHITE (-85 1635);
WIRE 17 -1 (-1700 425)(-1700 225);
WIRE 17 -1 (-1700 625)(-1700 425);
WIRE 17 -1 (-1700 825)(-1700 625);
WIRE 17 -1 (-1700 825)(-1700 1025);
WIRE 17 -1 (-1700 1225)(-1700 1025);
WIRE 17 -1 (-1700 1425)(-1700 1225);
WIRE 17 -1 (-1700 1625)(-1700 1425);
WIRE 17 -1 (-2800 1625)(-1700 1625);
FORCEPROP 2 LAST SIG_NAME P5E_CPU0_G3_TX_DN<7:0>
J 0
(-2760 1635);
DISPLAY 0.680851 (-2760 1635);
PAINT WHITE (-2760 1635);
WIRE 17 -1 (-1700 3600)(-1700 3400);
WIRE 17 -1 (-2800 3600)(-1700 3600);
FORCEPROP 2 LAST SIG_NAME P5E_CPU0_G3_TX_DN<15:8>
J 0
(-2760 3610);
DISPLAY 0.680851 (-2760 3610);
PAINT WHITE (-2760 3610);
WIRE 17 -1 (-1700 3400)(-1700 3200);
WIRE 17 -1 (-1700 3200)(-1700 3000);
WIRE 17 -1 (-1700 2800)(-1700 3000);
WIRE 17 -1 (-1700 2800)(-1700 2600);
WIRE 17 -1 (-1700 2600)(-1700 2400);
WIRE 17 -1 (-1700 2400)(-1700 2200);
WIRE 17 -1 (-325 3600)(-325 3400);
WIRE 17 -1 (-325 3600)(775 3600);
FORCEPROP 2 LAST SIG_NAME P5E_CPU0_G3_TX_C_DN<15:8>
J 0
(-85 3610);
DISPLAY 0.680851 (-85 3610);
PAINT WHITE (-85 3610);
WIRE 17 -1 (-325 2600)(-325 2400);
WIRE 17 -1 (-325 2800)(-325 2600);
WIRE 17 -1 (-325 2400)(-325 2200);
WIRE 17 -1 (-325 2800)(-325 3000);
WIRE 17 -1 (-325 3200)(-325 3000);
WIRE 17 -1 (-325 3400)(-325 3200);
WIRE 16 -1 (-1000 1400)(-1600 1400);
WIRE 16 -1 (3650 3525)(4275 3525);
WIRE 16 -1 (3650 3325)(4275 3325);
WIRE 16 -1 (3650 3125)(4275 3125);
WIRE 16 -1 (3650 2975)(4075 2975);
WIRE 16 -1 (3650 2775)(4075 2775);
WIRE 16 -1 (3650 2325)(4275 2325);
WIRE 16 -1 (3650 2125)(4275 2125);
WIRE 16 -1 (3650 1150)(4275 1150);
WIRE 16 -1 (3650 350)(4275 350);
WIRE 16 -1 (3500 1550)(2650 1550);
WIRE 16 -1 (3500 1600)(2900 1600);
WIRE 16 -1 (3650 1200)(4075 1200);
WIRE 16 -1 (3650 950)(4275 950);
WIRE 16 -1 (3650 3575)(4075 3575);
WIRE 16 -1 (3650 3375)(4075 3375);
WIRE 16 -1 (3650 3175)(4075 3175);
WIRE 16 -1 (3650 2925)(4275 2925);
WIRE 16 -1 (3650 1600)(4075 1600);
WIRE 16 -1 (3650 1550)(4275 1550);
WIRE 16 -1 (3650 1350)(4275 1350);
WIRE 16 -1 (3650 1400)(4075 1400);
WIRE 16 -1 (3650 1000)(4075 1000);
WIRE 16 -1 (3500 3575)(2900 3575);
WIRE 16 -1 (3500 3375)(2900 3375);
WIRE 16 -1 (3500 3175)(2900 3175);
WIRE 16 -1 (3500 3525)(2650 3525);
WIRE 16 -1 (3500 3325)(2650 3325);
WIRE 16 -1 (3500 2975)(2900 2975);
WIRE 16 -1 (3500 2575)(2900 2575);
WIRE 16 -1 (3500 2775)(2900 2775);
WIRE 16 -1 (3500 2925)(2650 2925);
WIRE 16 -1 (3500 2375)(2900 2375);
WIRE 16 -1 (3500 2525)(2650 2525);
WIRE 16 -1 (3500 1400)(2900 1400);
WIRE 16 -1 (3500 1200)(2900 1200);
WIRE 16 -1 (3500 1000)(2900 1000);
WIRE 16 -1 (3500 400)(2900 400);
WIRE 16 -1 (3500 200)(2900 200);
WIRE 16 -1 (3500 750)(2650 750);
WIRE 16 -1 (3500 950)(2650 950);
WIRE 16 -1 (3500 350)(2650 350);
WIRE 16 -1 (3500 150)(2650 150);
WIRE 16 -1 (-850 2325)(-225 2325);
WIRE 16 -1 (-1000 1550)(-1850 1550);
WIRE 16 -1 (-1000 1000)(-1600 1000);
WIRE 16 -1 (-1000 950)(-1850 950);
WIRE 16 -1 (-1000 750)(-1850 750);
WIRE 16 -1 (-1000 600)(-1600 600);
WIRE 16 -1 (-1000 400)(-1600 400);
WIRE 16 -1 (-1000 350)(-1850 350);
WIRE 16 -1 (-850 1400)(-425 1400);
WIRE 16 -1 (-850 1600)(-425 1600);
WIRE 16 -1 (-850 2175)(-425 2175);
WIRE 16 -1 (-850 3525)(-225 3525);
WIRE 16 -1 (-850 3575)(-425 3575);
WIRE 16 -1 (-850 150)(-225 150);
WIRE 16 -1 (-850 200)(-425 200);
WIRE 16 -1 (-850 550)(-225 550);
WIRE 16 -1 (-850 600)(-425 600);
WIRE 16 -1 (-850 750)(-225 750);
WIRE 16 -1 (-850 800)(-425 800);
WIRE 16 -1 (-850 950)(-225 950);
WIRE 16 -1 (-850 1000)(-425 1000);
WIRE 16 -1 (-850 1200)(-425 1200);
WIRE 16 -1 (-850 2525)(-225 2525);
WIRE 16 -1 (-850 2575)(-425 2575);
WIRE 16 -1 (-850 2775)(-425 2775);
WIRE 16 -1 (-850 2975)(-425 2975);
WIRE 16 -1 (-850 3125)(-225 3125);
WIRE 16 -1 (-850 3175)(-425 3175);
WIRE 16 -1 (-850 2375)(-425 2375);
WIRE 16 -1 (-850 3325)(-225 3325);
WIRE 16 -1 (-850 3375)(-425 3375);
WIRE 16 -1 (-1000 2775)(-1600 2775);
WIRE 16 -1 (-1000 3325)(-1850 3325);
WIRE 16 -1 (-1000 3525)(-1850 3525);
WIRE 16 -1 (-1000 2725)(-1850 2725);
WIRE 16 -1 (-1000 2925)(-1850 2925);
WIRE 16 -1 (-1000 2175)(-1600 2175);
WIRE 16 -1 (-1000 2975)(-1600 2975);
WIRE 16 -1 (-1000 2375)(-1600 2375);
WIRE 16 -1 (-1000 2575)(-1600 2575);
WIRE 16 -1 (-1000 3375)(-1600 3375);
WIRE 16 -1 (-1000 3175)(-1600 3175);
WIRE 16 -1 (-1000 3575)(-1600 3575);
WIRE 16 -1 (-1000 1350)(-1850 1350);
WIRE 16 -1 (-1000 1600)(-1600 1600);
WIRE 16 -1 (-1000 1150)(-1850 1150);
WIRE 16 -1 (-1000 1200)(-1600 1200);
WIRE 16 -1 (-1000 800)(-1600 800);
WIRE 16 -1 (-1000 200)(-1600 200);
WIRE 16 -1 (-1000 150)(-1850 150);
WIRE 16 -1 (-850 400)(-425 400);
WIRE 16 -1 (-1000 550)(-1850 550);
WIRE 16 -1 (3650 800)(4075 800);
WIRE 16 -1 (3650 750)(4275 750);
WIRE 16 -1 (3650 600)(4075 600);
WIRE 16 -1 (3650 550)(4275 550);
WIRE 16 -1 (3650 400)(4075 400);
WIRE 16 -1 (3650 200)(4075 200);
WIRE 16 -1 (3650 150)(4275 150);
WIRE 16 -1 (-850 2125)(-225 2125);
WIRE 16 -1 (-850 350)(-225 350);
WIRE 16 -1 (-850 1150)(-225 1150);
WIRE 16 -1 (-850 1350)(-225 1350);
WIRE 16 -1 (-1000 2325)(-1850 2325);
WIRE 16 -1 (-1000 2525)(-1850 2525);
WIRE 16 -1 (-1000 3125)(-1850 3125);
WIRE 16 -1 (-850 2725)(-225 2725);
WIRE 16 -1 (-850 2925)(-225 2925);
WIRE 16 -1 (-1000 2125)(-1850 2125);
WIRE 16 -1 (-850 1550)(-225 1550);
WIRE 16 -1 (3500 550)(2650 550);
WIRE 16 -1 (3500 600)(2900 600);
WIRE 16 -1 (3500 800)(2900 800);
WIRE 16 -1 (3500 1150)(2650 1150);
WIRE 16 -1 (3500 1350)(2650 1350);
WIRE 16 -1 (3500 2325)(2650 2325);
WIRE 16 -1 (3500 2725)(2650 2725);
WIRE 16 -1 (3500 3125)(2650 3125);
WIRE 16 -1 (3500 2125)(2650 2125);
WIRE 16 -1 (3500 2175)(2900 2175);
WIRE 16 -1 (3650 2375)(4075 2375);
WIRE 16 -1 (3650 2525)(4275 2525);
WIRE 16 -1 (3650 2575)(4075 2575);
WIRE 16 -1 (3650 2725)(4275 2725);
WIRE 16 -1 (3650 2175)(4075 2175);
FORCENOTE
CPU0 PCIE G3 TX
(-2475 -450) 0;
DISPLAY LEFT (-2475 -450);
DISPLAY 4.148936 (-2475 -450);
PAINT WHITE (-2475 -450);
FORCENOTE
CPU1 PCIE P0 TX
(2000 -500) 0;
DISPLAY LEFT (2000 -500);
DISPLAY 4.148936 (2000 -500);
PAINT WHITE (2000 -500);
QUIT
